(kicad_sch
	(version 20250114)
	(generator "eeschema")
	(generator_version "9.0")
	(paper "A3")
	(title_block
		(title "Antmicro Baseboard for Jetson AGX Thor")
		(date "2026-02-17")
		(rev "1.1.0")
		(company "Antmicro Ltd")
		(comment 1 "www.antmicro.com")
	)
	(rectangle
		(start 209.55 139.7)
		(end 179.07 165.1)
		(stroke
			(width 0)
			(type dash)
		)
		(fill
			(type none)
		)
	)
	(rectangle
		(start 240.03 152.4)
		(end 209.55 170.18)
		(stroke
			(width 0)
			(type solid)
			(color 255 0 0 1)
		)
		(fill
			(type none)
		)
	)
	(rectangle
		(start 373.38 167.64)
		(end 402.59 250.19)
		(stroke
			(width 0)
			(type dash)
		)
		(fill
			(type none)
		)
	)
	(text "Will be under AGX"
		(exclude_from_sim no)
		(at 242.316 169.926 90)
		(effects
			(font
				(size 1.27 1.27)
				(color 255 0 0 1)
			)
			(justify left)
		)
	)
	(text "Note:\nPopulate if using FMC \nconn. as host"
		(exclude_from_sim no)
		(at 376.936 172.212 0)
		(effects
			(font
				(size 1.27 1.27)
			)
			(justify left)
		)
	)
	(text "FMC Module ID"
		(exclude_from_sim no)
		(at 329.184 167.386 0)
		(effects
			(font
				(size 2.54 2.54)
				(thickness 0.508)
				(bold yes)
			)
			(justify left bottom)
		)
	)
	(text "FMC+ expansion connector"
		(exclude_from_sim no)
		(at 188.214 18.542 0)
		(effects
			(font
				(size 2.54 2.54)
				(thickness 0.508)
				(bold yes)
			)
			(justify left bottom)
		)
	)
	(text "I2C addres (7-bit): \n- EEPROM: 0x50 + ADDR[1..0]\n- UUID: 0x58 + ADDR[1..0]"
		(exclude_from_sim no)
		(at 332.994 199.644 0)
		(effects
			(font
				(size 1.27 1.27)
			)
			(justify left)
		)
	)
	(text "Note:\nFlip DNP if using FMC \nconn. as host"
		(exclude_from_sim no)
		(at 206.756 144.78 0)
		(effects
			(font
				(size 1.27 1.27)
			)
			(justify right)
		)
	)
	(text "Power connector"
		(exclude_from_sim no)
		(at 326.898 211.074 0)
		(effects
			(font
				(size 2.54 2.54)
				(thickness 0.508)
				(bold yes)
			)
			(justify left bottom)
		)
	)
	(junction
		(at 57.15 191.77)
		(diameter 0)
		(color 0 0 0 0)
	)
	(junction
		(at 247.65 67.31)
		(diameter 0)
		(color 0 0 0 0)
	)
	(junction
		(at 212.09 250.19)
		(diameter 0)
		(color 0 0 0 0)
	)
	(junction
		(at 119.38 166.37)
		(diameter 0)
		(color 0 0 0 0)
	)
	(junction
		(at 237.49 232.41)
		(diameter 0)
		(color 0 0 0 0)
	)
	(junction
		(at 57.15 194.31)
		(diameter 0)
		(color 0 0 0 0)
	)
	(junction
		(at 110.49 62.23)
		(diameter 0)
		(color 0 0 0 0)
	)
	(junction
		(at 247.65 34.29)
		(diameter 0)
		(color 0 0 0 0)
	)
	(junction
		(at 354.33 87.63)
		(diameter 0)
		(color 0 0 0 0)
	)
	(junction
		(at 191.77 46.99)
		(diameter 0)
		(color 0 0 0 0)
	)
	(junction
		(at 339.09 238.76)
		(diameter 0)
		(color 0 0 0 0)
	)
	(junction
		(at 339.09 236.22)
		(diameter 0)
		(color 0 0 0 0)
	)
	(junction
		(at 82.55 207.01)
		(diameter 0)
		(color 0 0 0 0)
	)
	(junction
		(at 119.38 212.09)
		(diameter 0)
		(color 0 0 0 0)
	)
	(junction
		(at 354.33 77.47)
		(diameter 0)
		(color 0 0 0 0)
	)
	(junction
		(at 212.09 196.85)
		(diameter 0)
		(color 0 0 0 0)
	)
	(junction
		(at 191.77 77.47)
		(diameter 0)
		(color 0 0 0 0)
	)
	(junction
		(at 119.38 227.33)
		(diameter 0)
		(color 0 0 0 0)
	)
	(junction
		(at 237.49 163.83)
		(diameter 0)
		(color 0 0 0 0)
	)
	(junction
		(at 354.33 128.27)
		(diameter 0)
		(color 0 0 0 0)
	)
	(junction
		(at 354.33 100.33)
		(diameter 0)
		(color 0 0 0 0)
	)
	(junction
		(at 110.49 100.33)
		(diameter 0)
		(color 0 0 0 0)
	)
	(junction
		(at 273.05 90.17)
		(diameter 0)
		(color 0 0 0 0)
	)
	(junction
		(at 57.15 242.57)
		(diameter 0)
		(color 0 0 0 0)
	)
	(junction
		(at 144.78 252.73)
		(diameter 0)
		(color 0 0 0 0)
	)
	(junction
		(at 328.93 41.91)
		(diameter 0)
		(color 0 0 0 0)
	)
	(junction
		(at 273.05 67.31)
		(diameter 0)
		(color 0 0 0 0)
	)
	(junction
		(at 85.09 102.87)
		(diameter 0)
		(color 0 0 0 0)
	)
	(junction
		(at 212.09 168.91)
		(diameter 0)
		(color 0 0 0 0)
	)
	(junction
		(at 212.09 237.49)
		(diameter 0)
		(color 0 0 0 0)
	)
	(junction
		(at 166.37 87.63)
		(diameter 0)
		(color 0 0 0 0)
	)
	(junction
		(at 237.49 161.29)
		(diameter 0)
		(color 0 0 0 0)
	)
	(junction
		(at 110.49 46.99)
		(diameter 0)
		(color 0 0 0 0)
	)
	(junction
		(at 144.78 247.65)
		(diameter 0)
		(color 0 0 0 0)
	)
	(junction
		(at 57.15 181.61)
		(diameter 0)
		(color 0 0 0 0)
	)
	(junction
		(at 57.15 232.41)
		(diameter 0)
		(color 0 0 0 0)
	)
	(junction
		(at 212.09 229.87)
		(diameter 0)
		(color 0 0 0 0)
	)
	(junction
		(at 328.93 34.29)
		(diameter 0)
		(color 0 0 0 0)
	)
	(junction
		(at 82.55 237.49)
		(diameter 0)
		(color 0 0 0 0)
	)
	(junction
		(at 212.09 227.33)
		(diameter 0)
		(color 0 0 0 0)
	)
	(junction
		(at 57.15 161.29)
		(diameter 0)
		(color 0 0 0 0)
	)
	(junction
		(at 57.15 173.99)
		(diameter 0)
		(color 0 0 0 0)
	)
	(junction
		(at 273.05 39.37)
		(diameter 0)
		(color 0 0 0 0)
	)
	(junction
		(at 82.55 166.37)
		(diameter 0)
		(color 0 0 0 0)
	)
	(junction
		(at 212.09 247.65)
		(diameter 0)
		(color 0 0 0 0)
	)
	(junction
		(at 273.05 110.49)
		(diameter 0)
		(color 0 0 0 0)
	)
	(junction
		(at 354.33 90.17)
		(diameter 0)
		(color 0 0 0 0)
	)
	(junction
		(at 354.33 67.31)
		(diameter 0)
		(color 0 0 0 0)
	)
	(junction
		(at 119.38 234.95)
		(diameter 0)
		(color 0 0 0 0)
	)
	(junction
		(at 339.09 241.3)
		(diameter 0)
		(color 0 0 0 0)
	)
	(junction
		(at 144.78 186.69)
		(diameter 0)
		(color 0 0 0 0)
	)
	(junction
		(at 144.78 209.55)
		(diameter 0)
		(color 0 0 0 0)
	)
	(junction
		(at 354.33 107.95)
		(diameter 0)
		(color 0 0 0 0)
	)
	(junction
		(at 119.38 250.19)
		(diameter 0)
		(color 0 0 0 0)
	)
	(junction
		(at 191.77 107.95)
		(diameter 0)
		(color 0 0 0 0)
	)
	(junction
		(at 328.93 95.25)
		(diameter 0)
		(color 0 0 0 0)
	)
	(junction
		(at 237.49 201.93)
		(diameter 0)
		(color 0 0 0 0)
	)
	(junction
		(at 82.55 179.07)
		(diameter 0)
		(color 0 0 0 0)
	)
	(junction
		(at 57.15 214.63)
		(diameter 0)
		(color 0 0 0 0)
	)
	(junction
		(at 191.77 39.37)
		(diameter 0)
		(color 0 0 0 0)
	)
	(junction
		(at 328.93 125.73)
		(diameter 0)
		(color 0 0 0 0)
	)
	(junction
		(at 85.09 72.39)
		(diameter 0)
		(color 0 0 0 0)
	)
	(junction
		(at 72.39 31.75)
		(diameter 0)
		(color 0 0 0 0)
	)
	(junction
		(at 110.49 54.61)
		(diameter 0)
		(color 0 0 0 0)
	)
	(junction
		(at 275.59 115.57)
		(diameter 0)
		(color 0 0 0 0)
	)
	(junction
		(at 110.49 77.47)
		(diameter 0)
		(color 0 0 0 0)
	)
	(junction
		(at 237.49 173.99)
		(diameter 0)
		(color 0 0 0 0)
	)
	(junction
		(at 354.33 110.49)
		(diameter 0)
		(color 0 0 0 0)
	)
	(junction
		(at 85.09 118.11)
		(diameter 0)
		(color 0 0 0 0)
	)
	(junction
		(at 247.65 120.65)
		(diameter 0)
		(color 0 0 0 0)
	)
	(junction
		(at 119.38 173.99)
		(diameter 0)
		(color 0 0 0 0)
	)
	(junction
		(at 273.05 87.63)
		(diameter 0)
		(color 0 0 0 0)
	)
	(junction
		(at 144.78 163.83)
		(diameter 0)
		(color 0 0 0 0)
	)
	(junction
		(at 191.77 54.61)
		(diameter 0)
		(color 0 0 0 0)
	)
	(junction
		(at 166.37 57.15)
		(diameter 0)
		(color 0 0 0 0)
	)
	(junction
		(at 354.33 97.79)
		(diameter 0)
		(color 0 0 0 0)
	)
	(junction
		(at 273.05 128.27)
		(diameter 0)
		(color 0 0 0 0)
	)
	(junction
		(at 212.09 219.71)
		(diameter 0)
		(color 0 0 0 0)
	)
	(junction
		(at 85.09 57.15)
		(diameter 0)
		(color 0 0 0 0)
	)
	(junction
		(at 166.37 95.25)
		(diameter 0)
		(color 0 0 0 0)
	)
	(junction
		(at 57.15 234.95)
		(diameter 0)
		(color 0 0 0 0)
	)
	(junction
		(at 166.37 80.01)
		(diameter 0)
		(color 0 0 0 0)
	)
	(junction
		(at 191.77 100.33)
		(diameter 0)
		(color 0 0 0 0)
	)
	(junction
		(at 144.78 224.79)
		(diameter 0)
		(color 0 0 0 0)
	)
	(junction
		(at 237.49 212.09)
		(diameter 0)
		(color 0 0 0 0)
	)
	(junction
		(at 237.49 204.47)
		(diameter 0)
		(color 0 0 0 0)
	)
	(junction
		(at 82.55 189.23)
		(diameter 0)
		(color 0 0 0 0)
	)
	(junction
		(at 339.09 228.6)
		(diameter 0)
		(color 0 0 0 0)
	)
	(junction
		(at 328.93 64.77)
		(diameter 0)
		(color 0 0 0 0)
	)
	(junction
		(at 273.05 77.47)
		(diameter 0)
		(color 0 0 0 0)
	)
	(junction
		(at 166.37 125.73)
		(diameter 0)
		(color 0 0 0 0)
	)
	(junction
		(at 57.15 163.83)
		(diameter 0)
		(color 0 0 0 0)
	)
	(junction
		(at 247.65 59.69)
		(diameter 0)
		(color 0 0 0 0)
	)
	(junction
		(at 191.77 115.57)
		(diameter 0)
		(color 0 0 0 0)
	)
	(junction
		(at 212.09 199.39)
		(diameter 0)
		(color 0 0 0 0)
	)
	(junction
		(at 191.77 128.27)
		(diameter 0)
		(color 0 0 0 0)
	)
	(junction
		(at 82.55 227.33)
		(diameter 0)
		(color 0 0 0 0)
	)
	(junction
		(at 212.09 186.69)
		(diameter 0)
		(color 0 0 0 0)
	)
	(junction
		(at 57.15 184.15)
		(diameter 0)
		(color 0 0 0 0)
	)
	(junction
		(at 86.36 242.57)
		(diameter 0)
		(color 0 0 0 0)
	)
	(junction
		(at 144.78 240.03)
		(diameter 0)
		(color 0 0 0 0)
	)
	(junction
		(at 85.09 125.73)
		(diameter 0)
		(color 0 0 0 0)
	)
	(junction
		(at 328.93 44.45)
		(diameter 0)
		(color 0 0 0 0)
	)
	(junction
		(at 82.55 229.87)
		(diameter 0)
		(color 0 0 0 0)
	)
	(junction
		(at 245.11 118.11)
		(diameter 0)
		(color 0 0 0 0)
	)
	(junction
		(at 237.49 224.79)
		(diameter 0)
		(color 0 0 0 0)
	)
	(junction
		(at 237.49 194.31)
		(diameter 0)
		(color 0 0 0 0)
	)
	(junction
		(at 119.38 204.47)
		(diameter 0)
		(color 0 0 0 0)
	)
	(junction
		(at 237.49 252.73)
		(diameter 0)
		(color 0 0 0 0)
	)
	(junction
		(at 237.49 234.95)
		(diameter 0)
		(color 0 0 0 0)
	)
	(junction
		(at 354.33 80.01)
		(diameter 0)
		(color 0 0 0 0)
	)
	(junction
		(at 57.15 171.45)
		(diameter 0)
		(color 0 0 0 0)
	)
	(junction
		(at 166.37 110.49)
		(diameter 0)
		(color 0 0 0 0)
	)
	(junction
		(at 110.49 85.09)
		(diameter 0)
		(color 0 0 0 0)
	)
	(junction
		(at 110.49 39.37)
		(diameter 0)
		(color 0 0 0 0)
	)
	(junction
		(at 110.49 123.19)
		(diameter 0)
		(color 0 0 0 0)
	)
	(junction
		(at 82.55 158.75)
		(diameter 0)
		(color 0 0 0 0)
	)
	(junction
		(at 354.33 118.11)
		(diameter 0)
		(color 0 0 0 0)
	)
	(junction
		(at 86.36 245.11)
		(diameter 0)
		(color 0 0 0 0)
	)
	(junction
		(at 110.49 128.27)
		(diameter 0)
		(color 0 0 0 0)
	)
	(junction
		(at 237.49 245.11)
		(diameter 0)
		(color 0 0 0 0)
	)
	(junction
		(at 273.05 49.53)
		(diameter 0)
		(color 0 0 0 0)
	)
	(junction
		(at 191.77 92.71)
		(diameter 0)
		(color 0 0 0 0)
	)
	(junction
		(at 273.05 46.99)
		(diameter 0)
		(color 0 0 0 0)
	)
	(junction
		(at 85.09 80.01)
		(diameter 0)
		(color 0 0 0 0)
	)
	(junction
		(at 82.55 168.91)
		(diameter 0)
		(color 0 0 0 0)
	)
	(junction
		(at 57.15 245.11)
		(diameter 0)
		(color 0 0 0 0)
	)
	(junction
		(at 247.65 82.55)
		(diameter 0)
		(color 0 0 0 0)
	)
	(junction
		(at 354.33 57.15)
		(diameter 0)
		(color 0 0 0 0)
	)
	(junction
		(at 57.15 252.73)
		(diameter 0)
		(color 0 0 0 0)
	)
	(junction
		(at 212.09 179.07)
		(diameter 0)
		(color 0 0 0 0)
	)
	(junction
		(at 212.09 189.23)
		(diameter 0)
		(color 0 0 0 0)
	)
	(junction
		(at 57.15 201.93)
		(diameter 0)
		(color 0 0 0 0)
	)
	(junction
		(at 82.55 186.69)
		(diameter 0)
		(color 0 0 0 0)
	)
	(junction
		(at 237.49 242.57)
		(diameter 0)
		(color 0 0 0 0)
	)
	(junction
		(at 166.37 102.87)
		(diameter 0)
		(color 0 0 0 0)
	)
	(junction
		(at 57.15 222.25)
		(diameter 0)
		(color 0 0 0 0)
	)
	(junction
		(at 328.93 54.61)
		(diameter 0)
		(color 0 0 0 0)
	)
	(junction
		(at 354.33 120.65)
		(diameter 0)
		(color 0 0 0 0)
	)
	(junction
		(at 393.7 185.42)
		(diameter 0)
		(color 0 0 0 0)
	)
	(junction
		(at 328.93 102.87)
		(diameter 0)
		(color 0 0 0 0)
	)
	(junction
		(at 247.65 44.45)
		(diameter 0)
		(color 0 0 0 0)
	)
	(junction
		(at 354.33 49.53)
		(diameter 0)
		(color 0 0 0 0)
	)
	(junction
		(at 354.33 39.37)
		(diameter 0)
		(color 0 0 0 0)
	)
	(junction
		(at 119.38 158.75)
		(diameter 0)
		(color 0 0 0 0)
	)
	(junction
		(at 85.09 87.63)
		(diameter 0)
		(color 0 0 0 0)
	)
	(junction
		(at 328.93 74.93)
		(diameter 0)
		(color 0 0 0 0)
	)
	(junction
		(at 328.93 85.09)
		(diameter 0)
		(color 0 0 0 0)
	)
	(junction
		(at 144.78 161.29)
		(diameter 0)
		(color 0 0 0 0)
	)
	(junction
		(at 85.09 110.49)
		(diameter 0)
		(color 0 0 0 0)
	)
	(junction
		(at 273.05 100.33)
		(diameter 0)
		(color 0 0 0 0)
	)
	(junction
		(at 247.65 90.17)
		(diameter 0)
		(color 0 0 0 0)
	)
	(junction
		(at 144.78 201.93)
		(diameter 0)
		(color 0 0 0 0)
	)
	(junction
		(at 85.09 41.91)
		(diameter 0)
		(color 0 0 0 0)
	)
	(junction
		(at 82.55 199.39)
		(diameter 0)
		(color 0 0 0 0)
	)
	(junction
		(at 354.33 59.69)
		(diameter 0)
		(color 0 0 0 0)
	)
	(junction
		(at 247.65 97.79)
		(diameter 0)
		(color 0 0 0 0)
	)
	(junction
		(at 191.77 153.67)
		(diameter 0)
		(color 0 0 0 0)
	)
	(junction
		(at 57.15 212.09)
		(diameter 0)
		(color 0 0 0 0)
	)
	(junction
		(at 82.55 176.53)
		(diameter 0)
		(color 0 0 0 0)
	)
	(junction
		(at 110.49 107.95)
		(diameter 0)
		(color 0 0 0 0)
	)
	(junction
		(at 353.06 187.96)
		(diameter 0)
		(color 0 0 0 0)
	)
	(junction
		(at 273.05 36.83)
		(diameter 0)
		(color 0 0 0 0)
	)
	(junction
		(at 237.49 214.63)
		(diameter 0)
		(color 0 0 0 0)
	)
	(junction
		(at 191.77 62.23)
		(diameter 0)
		(color 0 0 0 0)
	)
	(junction
		(at 110.49 69.85)
		(diameter 0)
		(color 0 0 0 0)
	)
	(junction
		(at 119.38 219.71)
		(diameter 0)
		(color 0 0 0 0)
	)
	(junction
		(at 358.14 176.53)
		(diameter 0)
		(color 0 0 0 0)
	)
	(junction
		(at 85.09 95.25)
		(diameter 0)
		(color 0 0 0 0)
	)
	(junction
		(at 237.49 184.15)
		(diameter 0)
		(color 0 0 0 0)
	)
	(junction
		(at 82.55 196.85)
		(diameter 0)
		(color 0 0 0 0)
	)
	(junction
		(at 166.37 49.53)
		(diameter 0)
		(color 0 0 0 0)
	)
	(junction
		(at 237.49 191.77)
		(diameter 0)
		(color 0 0 0 0)
	)
	(junction
		(at 237.49 181.61)
		(diameter 0)
		(color 0 0 0 0)
	)
	(junction
		(at 82.55 250.19)
		(diameter 0)
		(color 0 0 0 0)
	)
	(junction
		(at 110.49 36.83)
		(diameter 0)
		(color 0 0 0 0)
	)
	(junction
		(at 82.55 240.03)
		(diameter 0)
		(color 0 0 0 0)
	)
	(junction
		(at 212.09 217.17)
		(diameter 0)
		(color 0 0 0 0)
	)
	(junction
		(at 212.09 176.53)
		(diameter 0)
		(color 0 0 0 0)
	)
	(junction
		(at 166.37 34.29)
		(diameter 0)
		(color 0 0 0 0)
	)
	(junction
		(at 273.05 123.19)
		(diameter 0)
		(color 0 0 0 0)
	)
	(junction
		(at 273.05 59.69)
		(diameter 0)
		(color 0 0 0 0)
	)
	(junction
		(at 245.11 123.19)
		(diameter 0)
		(color 0 0 0 0)
	)
	(junction
		(at 212.09 240.03)
		(diameter 0)
		(color 0 0 0 0)
	)
	(junction
		(at 354.33 36.83)
		(diameter 0)
		(color 0 0 0 0)
	)
	(junction
		(at 354.33 46.99)
		(diameter 0)
		(color 0 0 0 0)
	)
	(junction
		(at 191.77 85.09)
		(diameter 0)
		(color 0 0 0 0)
	)
	(junction
		(at 212.09 209.55)
		(diameter 0)
		(color 0 0 0 0)
	)
	(junction
		(at 110.49 115.57)
		(diameter 0)
		(color 0 0 0 0)
	)
	(junction
		(at 82.55 209.55)
		(diameter 0)
		(color 0 0 0 0)
	)
	(junction
		(at 144.78 179.07)
		(diameter 0)
		(color 0 0 0 0)
	)
	(junction
		(at 110.49 92.71)
		(diameter 0)
		(color 0 0 0 0)
	)
	(junction
		(at 212.09 207.01)
		(diameter 0)
		(color 0 0 0 0)
	)
	(junction
		(at 191.77 69.85)
		(diameter 0)
		(color 0 0 0 0)
	)
	(junction
		(at 82.55 217.17)
		(diameter 0)
		(color 0 0 0 0)
	)
	(junction
		(at 85.09 64.77)
		(diameter 0)
		(color 0 0 0 0)
	)
	(junction
		(at 273.05 97.79)
		(diameter 0)
		(color 0 0 0 0)
	)
	(junction
		(at 273.05 118.11)
		(diameter 0)
		(color 0 0 0 0)
	)
	(junction
		(at 204.47 153.67)
		(diameter 0)
		(color 0 0 0 0)
	)
	(junction
		(at 57.15 224.79)
		(diameter 0)
		(color 0 0 0 0)
	)
	(junction
		(at 247.65 74.93)
		(diameter 0)
		(color 0 0 0 0)
	)
	(junction
		(at 247.65 41.91)
		(diameter 0)
		(color 0 0 0 0)
	)
	(junction
		(at 85.09 49.53)
		(diameter 0)
		(color 0 0 0 0)
	)
	(junction
		(at 354.33 69.85)
		(diameter 0)
		(color 0 0 0 0)
	)
	(junction
		(at 119.38 181.61)
		(diameter 0)
		(color 0 0 0 0)
	)
	(junction
		(at 191.77 123.19)
		(diameter 0)
		(color 0 0 0 0)
	)
	(junction
		(at 328.93 82.55)
		(diameter 0)
		(color 0 0 0 0)
	)
	(junction
		(at 273.05 69.85)
		(diameter 0)
		(color 0 0 0 0)
	)
	(junction
		(at 144.78 171.45)
		(diameter 0)
		(color 0 0 0 0)
	)
	(junction
		(at 144.78 194.31)
		(diameter 0)
		(color 0 0 0 0)
	)
	(junction
		(at 212.09 166.37)
		(diameter 0)
		(color 0 0 0 0)
	)
	(junction
		(at 328.93 62.23)
		(diameter 0)
		(color 0 0 0 0)
	)
	(junction
		(at 237.49 222.25)
		(diameter 0)
		(color 0 0 0 0)
	)
	(junction
		(at 166.37 41.91)
		(diameter 0)
		(color 0 0 0 0)
	)
	(junction
		(at 328.93 115.57)
		(diameter 0)
		(color 0 0 0 0)
	)
	(junction
		(at 82.55 219.71)
		(diameter 0)
		(color 0 0 0 0)
	)
	(junction
		(at 328.93 52.07)
		(diameter 0)
		(color 0 0 0 0)
	)
	(junction
		(at 166.37 118.11)
		(diameter 0)
		(color 0 0 0 0)
	)
	(junction
		(at 144.78 217.17)
		(diameter 0)
		(color 0 0 0 0)
	)
	(junction
		(at 119.38 189.23)
		(diameter 0)
		(color 0 0 0 0)
	)
	(junction
		(at 82.55 247.65)
		(diameter 0)
		(color 0 0 0 0)
	)
	(junction
		(at 328.93 72.39)
		(diameter 0)
		(color 0 0 0 0)
	)
	(junction
		(at 273.05 80.01)
		(diameter 0)
		(color 0 0 0 0)
	)
	(junction
		(at 57.15 204.47)
		(diameter 0)
		(color 0 0 0 0)
	)
	(junction
		(at 191.77 36.83)
		(diameter 0)
		(color 0 0 0 0)
	)
	(junction
		(at 247.65 52.07)
		(diameter 0)
		(color 0 0 0 0)
	)
	(junction
		(at 212.09 158.75)
		(diameter 0)
		(color 0 0 0 0)
	)
	(junction
		(at 166.37 72.39)
		(diameter 0)
		(color 0 0 0 0)
	)
	(junction
		(at 328.93 105.41)
		(diameter 0)
		(color 0 0 0 0)
	)
	(junction
		(at 328.93 92.71)
		(diameter 0)
		(color 0 0 0 0)
	)
	(junction
		(at 166.37 64.77)
		(diameter 0)
		(color 0 0 0 0)
	)
	(junction
		(at 328.93 113.03)
		(diameter 0)
		(color 0 0 0 0)
	)
	(junction
		(at 273.05 57.15)
		(diameter 0)
		(color 0 0 0 0)
	)
	(junction
		(at 247.65 125.73)
		(diameter 0)
		(color 0 0 0 0)
	)
	(junction
		(at 144.78 232.41)
		(diameter 0)
		(color 0 0 0 0)
	)
	(junction
		(at 328.93 123.19)
		(diameter 0)
		(color 0 0 0 0)
	)
	(junction
		(at 119.38 242.57)
		(diameter 0)
		(color 0 0 0 0)
	)
	(junction
		(at 273.05 107.95)
		(diameter 0)
		(color 0 0 0 0)
	)
	(junction
		(at 119.38 196.85)
		(diameter 0)
		(color 0 0 0 0)
	)
	(junction
		(at 237.49 171.45)
		(diameter 0)
		(color 0 0 0 0)
	)
	(no_connect
		(at 120.65 179.07)
	)
	(no_connect
		(at 330.2 107.95)
	)
	(no_connect
		(at 167.64 54.61)
	)
	(no_connect
		(at 109.22 110.49)
	)
	(no_connect
		(at 167.64 115.57)
	)
	(no_connect
		(at 58.42 219.71)
	)
	(no_connect
		(at 167.64 97.79)
	)
	(no_connect
		(at 353.06 82.55)
	)
	(no_connect
		(at 86.36 123.19)
	)
	(no_connect
		(at 190.5 59.69)
	)
	(no_connect
		(at 58.42 247.65)
	)
	(no_connect
		(at 190.5 72.39)
	)
	(no_connect
		(at 190.5 74.93)
	)
	(no_connect
		(at 167.64 69.85)
	)
	(no_connect
		(at 120.65 237.49)
	)
	(no_connect
		(at 120.65 186.69)
	)
	(no_connect
		(at 190.5 34.29)
	)
	(no_connect
		(at 58.42 189.23)
	)
	(no_connect
		(at 58.42 229.87)
	)
	(no_connect
		(at 143.51 191.77)
	)
	(no_connect
		(at 143.51 158.75)
	)
	(no_connect
		(at 86.36 115.57)
	)
	(no_connect
		(at 58.42 209.55)
	)
	(no_connect
		(at 167.64 44.45)
	)
	(no_connect
		(at 330.2 90.17)
	)
	(no_connect
		(at 120.65 224.79)
	)
	(no_connect
		(at 81.28 224.79)
	)
	(no_connect
		(at 213.36 201.93)
	)
	(no_connect
		(at 120.65 217.17)
	)
	(no_connect
		(at 190.5 113.03)
	)
	(no_connect
		(at 81.28 214.63)
	)
	(no_connect
		(at 167.64 90.17)
	)
	(no_connect
		(at 58.42 156.21)
	)
	(no_connect
		(at 167.64 77.47)
	)
	(no_connect
		(at 58.42 196.85)
	)
	(no_connect
		(at 248.92 102.87)
	)
	(no_connect
		(at 120.65 240.03)
	)
	(no_connect
		(at 353.06 95.25)
	)
	(no_connect
		(at 120.65 176.53)
	)
	(no_connect
		(at 58.42 168.91)
	)
	(no_connect
		(at 58.42 199.39)
	)
	(no_connect
		(at 190.5 87.63)
	)
	(no_connect
		(at 109.22 120.65)
	)
	(no_connect
		(at 213.36 173.99)
	)
	(no_connect
		(at 120.65 161.29)
	)
	(no_connect
		(at 58.42 186.69)
	)
	(no_connect
		(at 120.65 247.65)
	)
	(no_connect
		(at 213.36 214.63)
	)
	(no_connect
		(at 120.65 229.87)
	)
	(no_connect
		(at 353.06 105.41)
	)
	(no_connect
		(at 271.78 44.45)
	)
	(no_connect
		(at 167.64 59.69)
	)
	(no_connect
		(at 167.64 39.37)
	)
	(no_connect
		(at 143.51 214.63)
	)
	(no_connect
		(at 167.64 107.95)
	)
	(no_connect
		(at 81.28 191.77)
	)
	(no_connect
		(at 248.92 105.41)
	)
	(no_connect
		(at 330.2 87.63)
	)
	(no_connect
		(at 86.36 39.37)
	)
	(no_connect
		(at 120.65 222.25)
	)
	(no_connect
		(at 167.64 46.99)
	)
	(no_connect
		(at 271.78 41.91)
	)
	(no_connect
		(at 81.28 181.61)
	)
	(no_connect
		(at 58.42 179.07)
	)
	(no_connect
		(at 143.51 168.91)
	)
	(no_connect
		(at 190.5 82.55)
	)
	(no_connect
		(at 190.5 52.07)
	)
	(no_connect
		(at 143.51 196.85)
	)
	(no_connect
		(at 167.64 113.03)
	)
	(no_connect
		(at 167.64 85.09)
	)
	(no_connect
		(at 190.5 97.79)
	)
	(no_connect
		(at 167.64 82.55)
	)
	(no_connect
		(at 81.28 212.09)
	)
	(no_connect
		(at 190.5 80.01)
	)
	(no_connect
		(at 330.2 100.33)
	)
	(no_connect
		(at 353.06 102.87)
	)
	(no_connect
		(at 190.5 105.41)
	)
	(no_connect
		(at 143.51 176.53)
	)
	(no_connect
		(at 167.64 105.41)
	)
	(no_connect
		(at 143.51 204.47)
	)
	(no_connect
		(at 167.64 92.71)
	)
	(no_connect
		(at 248.92 36.83)
	)
	(no_connect
		(at 213.36 163.83)
	)
	(no_connect
		(at 120.65 191.77)
	)
	(no_connect
		(at 58.42 227.33)
	)
	(no_connect
		(at 120.65 171.45)
	)
	(no_connect
		(at 190.5 57.15)
	)
	(no_connect
		(at 236.22 168.91)
	)
	(no_connect
		(at 167.64 52.07)
	)
	(no_connect
		(at 190.5 118.11)
	)
	(no_connect
		(at 190.5 95.25)
	)
	(no_connect
		(at 81.28 201.93)
	)
	(no_connect
		(at 143.51 199.39)
	)
	(no_connect
		(at 143.51 222.25)
	)
	(no_connect
		(at 143.51 234.95)
	)
	(no_connect
		(at 248.92 113.03)
	)
	(no_connect
		(at 143.51 156.21)
	)
	(no_connect
		(at 190.5 41.91)
	)
	(no_connect
		(at 120.65 168.91)
	)
	(no_connect
		(at 236.22 156.21)
	)
	(no_connect
		(at 143.51 212.09)
	)
	(no_connect
		(at 167.64 123.19)
	)
	(no_connect
		(at 167.64 36.83)
	)
	(no_connect
		(at 330.2 118.11)
	)
	(no_connect
		(at 190.5 120.65)
	)
	(no_connect
		(at 248.92 110.49)
	)
	(no_connect
		(at 143.51 181.61)
	)
	(no_connect
		(at 81.28 163.83)
	)
	(no_connect
		(at 330.2 97.79)
	)
	(no_connect
		(at 190.5 102.87)
	)
	(no_connect
		(at 271.78 31.75)
	)
	(no_connect
		(at 86.36 113.03)
	)
	(no_connect
		(at 353.06 85.09)
	)
	(no_connect
		(at 58.42 176.53)
	)
	(no_connect
		(at 236.22 166.37)
	)
	(no_connect
		(at 58.42 240.03)
	)
	(no_connect
		(at 81.28 222.25)
	)
	(no_connect
		(at 143.51 184.15)
	)
	(no_connect
		(at 81.28 161.29)
	)
	(no_connect
		(at 143.51 189.23)
	)
	(no_connect
		(at 120.65 163.83)
	)
	(no_connect
		(at 143.51 229.87)
	)
	(no_connect
		(at 58.42 166.37)
	)
	(no_connect
		(at 248.92 100.33)
	)
	(no_connect
		(at 213.36 212.09)
	)
	(no_connect
		(at 167.64 74.93)
	)
	(no_connect
		(at 143.51 227.33)
	)
	(no_connect
		(at 58.42 158.75)
	)
	(no_connect
		(at 190.5 31.75)
	)
	(no_connect
		(at 167.64 62.23)
	)
	(no_connect
		(at 167.64 120.65)
	)
	(no_connect
		(at 143.51 245.11)
	)
	(no_connect
		(at 190.5 44.45)
	)
	(no_connect
		(at 120.65 184.15)
	)
	(no_connect
		(at 81.28 173.99)
	)
	(no_connect
		(at 86.36 120.65)
	)
	(no_connect
		(at 190.5 49.53)
	)
	(no_connect
		(at 120.65 245.11)
	)
	(no_connect
		(at 248.92 39.37)
	)
	(no_connect
		(at 353.06 113.03)
	)
	(no_connect
		(at 190.5 67.31)
	)
	(no_connect
		(at 353.06 92.71)
	)
	(no_connect
		(at 58.42 217.17)
	)
	(no_connect
		(at 271.78 34.29)
	)
	(no_connect
		(at 143.51 237.49)
	)
	(no_connect
		(at 143.51 242.57)
	)
	(no_connect
		(at 120.65 209.55)
	)
	(no_connect
		(at 143.51 219.71)
	)
	(no_connect
		(at 190.5 110.49)
	)
	(no_connect
		(at 167.64 100.33)
	)
	(no_connect
		(at 81.28 171.45)
	)
	(no_connect
		(at 353.06 123.19)
	)
	(no_connect
		(at 143.51 207.01)
	)
	(no_connect
		(at 330.2 120.65)
	)
	(no_connect
		(at 236.22 158.75)
	)
	(no_connect
		(at 81.28 194.31)
	)
	(no_connect
		(at 213.36 161.29)
	)
	(no_connect
		(at 81.28 184.15)
	)
	(no_connect
		(at 213.36 171.45)
	)
	(no_connect
		(at 120.65 207.01)
	)
	(no_connect
		(at 167.64 67.31)
	)
	(no_connect
		(at 353.06 125.73)
	)
	(no_connect
		(at 120.65 199.39)
	)
	(no_connect
		(at 213.36 204.47)
	)
	(no_connect
		(at 86.36 36.83)
	)
	(no_connect
		(at 190.5 90.17)
	)
	(no_connect
		(at 81.28 204.47)
	)
	(no_connect
		(at 120.65 214.63)
	)
	(no_connect
		(at 190.5 64.77)
	)
	(no_connect
		(at 109.22 113.03)
	)
	(no_connect
		(at 330.2 110.49)
	)
	(no_connect
		(at 58.42 207.01)
	)
	(no_connect
		(at 109.22 118.11)
	)
	(no_connect
		(at 120.65 194.31)
	)
	(no_connect
		(at 58.42 250.19)
	)
	(no_connect
		(at 58.42 237.49)
	)
	(no_connect
		(at 143.51 166.37)
	)
	(no_connect
		(at 120.65 201.93)
	)
	(no_connect
		(at 143.51 173.99)
	)
	(no_connect
		(at 353.06 115.57)
	)
	(no_connect
		(at 120.65 232.41)
	)
	(bus_entry
		(at 369.57 63.5)
		(size -1.27 1.27)
		(stroke
			(width 0)
			(type default)
		)
	)
	(bus_entry
		(at 289.56 248.92)
		(size -1.27 1.27)
		(stroke
			(width 0)
			(type default)
		)
	)
	(bus_entry
		(at 128.27 86.36)
		(size -1.27 1.27)
		(stroke
			(width 0)
			(type default)
		)
	)
	(bus_entry
		(at 172.72 233.68)
		(size 1.27 1.27)
		(stroke
			(width 0)
			(type default)
		)
	)
	(bus_entry
		(at 64.77 73.66)
		(size 1.27 1.27)
		(stroke
			(width 0)
			(type default)
		)
	)
	(bus_entry
		(at 294.64 50.8)
		(size -1.27 1.27)
		(stroke
			(width 0)
			(type default)
		)
	)
	(bus_entry
		(at 130.81 63.5)
		(size -1.27 1.27)
		(stroke
			(width 0)
			(type default)
		)
	)
	(bus_entry
		(at 289.56 236.22)
		(size -1.27 1.27)
		(stroke
			(width 0)
			(type default)
		)
	)
	(bus_entry
		(at 128.27 88.9)
		(size -1.27 1.27)
		(stroke
			(width 0)
			(type default)
		)
	)
	(bus_entry
		(at 313.69 45.72)
		(size 1.27 1.27)
		(stroke
			(width 0)
			(type default)
		)
	)
	(bus_entry
		(at 313.69 58.42)
		(size 1.27 1.27)
		(stroke
			(width 0)
			(type default)
		)
	)
	(bus_entry
		(at 69.85 53.34)
		(size 1.27 1.27)
		(stroke
			(width 0)
			(type default)
		)
	)
	(bus_entry
		(at 233.68 80.01)
		(size -1.27 -1.27)
		(stroke
			(width 0)
			(type default)
		)
	)
	(bus_entry
		(at 369.57 43.18)
		(size -1.27 1.27)
		(stroke
			(width 0)
			(type default)
		)
	)
	(bus_entry
		(at 289.56 208.28)
		(size -1.27 1.27)
		(stroke
			(width 0)
			(type default)
		)
	)
	(bus_entry
		(at 130.81 55.88)
		(size -1.27 1.27)
		(stroke
			(width 0)
			(type default)
		)
	)
	(bus_entry
		(at 69.85 66.04)
		(size 1.27 1.27)
		(stroke
			(width 0)
			(type default)
		)
	)
	(bus_entry
		(at 369.57 71.12)
		(size -1.27 1.27)
		(stroke
			(width 0)
			(type default)
		)
	)
	(bus_entry
		(at 313.69 68.58)
		(size 1.27 1.27)
		(stroke
			(width 0)
			(type default)
		)
	)
	(bus_entry
		(at 289.56 205.74)
		(size -1.27 1.27)
		(stroke
			(width 0)
			(type default)
		)
	)
	(bus_entry
		(at 369.57 40.64)
		(size -1.27 1.27)
		(stroke
			(width 0)
			(type default)
		)
	)
	(bus_entry
		(at 69.85 45.72)
		(size 1.27 1.27)
		(stroke
			(width 0)
			(type default)
		)
	)
	(bus_entry
		(at 233.68 77.47)
		(size -1.27 -1.27)
		(stroke
			(width 0)
			(type default)
		)
	)
	(bus_entry
		(at 232.41 63.5)
		(size 1.27 1.27)
		(stroke
			(width 0)
			(type default)
		)
	)
	(bus_entry
		(at 128.27 101.6)
		(size -1.27 1.27)
		(stroke
			(width 0)
			(type default)
		)
	)
	(bus_entry
		(at 64.77 76.2)
		(size 1.27 1.27)
		(stroke
			(width 0)
			(type default)
		)
	)
	(bus_entry
		(at 294.64 63.5)
		(size -1.27 1.27)
		(stroke
			(width 0)
			(type default)
		)
	)
	(bus_entry
		(at 64.77 88.9)
		(size 1.27 1.27)
		(stroke
			(width 0)
			(type default)
		)
	)
	(bus_entry
		(at 196.85 182.88)
		(size 1.27 1.27)
		(stroke
			(width 0)
			(type default)
		)
	)
	(bus_entry
		(at 289.56 218.44)
		(size -1.27 1.27)
		(stroke
			(width 0)
			(type default)
		)
	)
	(bus_entry
		(at 172.72 241.3)
		(size 1.27 1.27)
		(stroke
			(width 0)
			(type default)
		)
	)
	(bus_entry
		(at 172.72 220.98)
		(size 1.27 1.27)
		(stroke
			(width 0)
			(type default)
		)
	)
	(bus_entry
		(at 289.56 246.38)
		(size -1.27 1.27)
		(stroke
			(width 0)
			(type default)
		)
	)
	(bus_entry
		(at 130.81 43.18)
		(size -1.27 1.27)
		(stroke
			(width 0)
			(type default)
		)
	)
	(bus_entry
		(at 130.81 48.26)
		(size -1.27 1.27)
		(stroke
			(width 0)
			(type default)
		)
	)
	(bus_entry
		(at 130.81 40.64)
		(size -1.27 1.27)
		(stroke
			(width 0)
			(type default)
		)
	)
	(bus_entry
		(at 128.27 73.66)
		(size -1.27 1.27)
		(stroke
			(width 0)
			(type default)
		)
	)
	(bus_entry
		(at 325.12 177.8)
		(size 1.27 1.27)
		(stroke
			(width 0)
			(type default)
		)
	)
	(bus_entry
		(at 294.64 60.96)
		(size -1.27 1.27)
		(stroke
			(width 0)
			(type default)
		)
	)
	(bus_entry
		(at 289.56 215.9)
		(size -1.27 1.27)
		(stroke
			(width 0)
			(type default)
		)
	)
	(bus_entry
		(at 313.69 35.56)
		(size 1.27 1.27)
		(stroke
			(width 0)
			(type default)
		)
	)
	(bus_entry
		(at 252.73 187.96)
		(size -1.27 1.27)
		(stroke
			(width 0)
			(type default)
		)
	)
	(bus_entry
		(at 325.12 175.26)
		(size 1.27 1.27)
		(stroke
			(width 0)
			(type default)
		)
	)
	(bus_entry
		(at 232.41 53.34)
		(size 1.27 1.27)
		(stroke
			(width 0)
			(type default)
		)
	)
	(bus_entry
		(at 252.73 175.26)
		(size -1.27 1.27)
		(stroke
			(width 0)
			(type default)
		)
	)
	(bus_entry
		(at 313.69 48.26)
		(size 1.27 1.27)
		(stroke
			(width 0)
			(type default)
		)
	)
	(bus_entry
		(at 64.77 96.52)
		(size 1.27 1.27)
		(stroke
			(width 0)
			(type default)
		)
	)
	(bus_entry
		(at 130.81 50.8)
		(size -1.27 1.27)
		(stroke
			(width 0)
			(type default)
		)
	)
	(bus_entry
		(at 288.29 71.12)
		(size -1.27 1.27)
		(stroke
			(width 0)
			(type default)
		)
	)
	(bus_entry
		(at 64.77 81.28)
		(size 1.27 1.27)
		(stroke
			(width 0)
			(type default)
		)
	)
	(bus_entry
		(at 172.72 231.14)
		(size 1.27 1.27)
		(stroke
			(width 0)
			(type default)
		)
	)
	(bus_entry
		(at 196.85 190.5)
		(size 1.27 1.27)
		(stroke
			(width 0)
			(type default)
		)
	)
	(bus_entry
		(at 232.41 55.88)
		(size 1.27 1.27)
		(stroke
			(width 0)
			(type default)
		)
	)
	(bus_entry
		(at 64.77 91.44)
		(size 1.27 1.27)
		(stroke
			(width 0)
			(type default)
		)
	)
	(bus_entry
		(at 128.27 78.74)
		(size -1.27 1.27)
		(stroke
			(width 0)
			(type default)
		)
	)
	(bus_entry
		(at 252.73 198.12)
		(size -1.27 1.27)
		(stroke
			(width 0)
			(type default)
		)
	)
	(bus_entry
		(at 64.77 83.82)
		(size 1.27 1.27)
		(stroke
			(width 0)
			(type default)
		)
	)
	(bus_entry
		(at 232.41 68.58)
		(size 1.27 1.27)
		(stroke
			(width 0)
			(type default)
		)
	)
	(bus_entry
		(at 369.57 30.48)
		(size -1.27 1.27)
		(stroke
			(width 0)
			(type default)
		)
	)
	(bus_entry
		(at 130.81 30.48)
		(size -1.27 1.27)
		(stroke
			(width 0)
			(type default)
		)
	)
	(bus_entry
		(at 128.27 104.14)
		(size -1.27 1.27)
		(stroke
			(width 0)
			(type default)
		)
	)
	(bus_entry
		(at 64.77 106.68)
		(size 1.27 1.27)
		(stroke
			(width 0)
			(type default)
		)
	)
	(bus_entry
		(at 369.57 33.02)
		(size -1.27 1.27)
		(stroke
			(width 0)
			(type default)
		)
	)
	(bus_entry
		(at 252.73 177.8)
		(size -1.27 1.27)
		(stroke
			(width 0)
			(type default)
		)
	)
	(bus_entry
		(at 313.69 55.88)
		(size 1.27 1.27)
		(stroke
			(width 0)
			(type default)
		)
	)
	(bus_entry
		(at 233.68 85.09)
		(size -1.27 -1.27)
		(stroke
			(width 0)
			(type default)
		)
	)
	(bus_entry
		(at 288.29 73.66)
		(size -1.27 1.27)
		(stroke
			(width 0)
			(type default)
		)
	)
	(bus_entry
		(at 232.41 48.26)
		(size 1.27 1.27)
		(stroke
			(width 0)
			(type default)
		)
	)
	(bus_entry
		(at 128.27 71.12)
		(size -1.27 1.27)
		(stroke
			(width 0)
			(type default)
		)
	)
	(bus_entry
		(at 285.75 101.6)
		(size -1.27 1.27)
		(stroke
			(width 0)
			(type default)
		)
	)
	(bus_entry
		(at 232.41 71.12)
		(size 1.27 1.27)
		(stroke
			(width 0)
			(type default)
		)
	)
	(bus_entry
		(at 369.57 50.8)
		(size -1.27 1.27)
		(stroke
			(width 0)
			(type default)
		)
	)
	(bus_entry
		(at 69.85 43.18)
		(size 1.27 1.27)
		(stroke
			(width 0)
			(type default)
		)
	)
	(bus_entry
		(at 369.57 53.34)
		(size -1.27 1.27)
		(stroke
			(width 0)
			(type default)
		)
	)
	(bus_entry
		(at 69.85 60.96)
		(size 1.27 1.27)
		(stroke
			(width 0)
			(type default)
		)
	)
	(bus_entry
		(at 130.81 66.04)
		(size -1.27 1.27)
		(stroke
			(width 0)
			(type default)
		)
	)
	(bus_entry
		(at 293.37 83.82)
		(size -1.27 1.27)
		(stroke
			(width 0)
			(type default)
		)
	)
	(bus_entry
		(at 294.64 53.34)
		(size -1.27 1.27)
		(stroke
			(width 0)
			(type default)
		)
	)
	(bus_entry
		(at 313.69 38.1)
		(size 1.27 1.27)
		(stroke
			(width 0)
			(type default)
		)
	)
	(bus_entry
		(at 128.27 96.52)
		(size -1.27 1.27)
		(stroke
			(width 0)
			(type default)
		)
	)
	(bus_entry
		(at 232.41 60.96)
		(size 1.27 1.27)
		(stroke
			(width 0)
			(type default)
		)
	)
	(bus_entry
		(at 64.77 99.06)
		(size 1.27 1.27)
		(stroke
			(width 0)
			(type default)
		)
	)
	(bus_entry
		(at 196.85 180.34)
		(size 1.27 1.27)
		(stroke
			(width 0)
			(type default)
		)
	)
	(bus_entry
		(at 289.56 226.06)
		(size -1.27 1.27)
		(stroke
			(width 0)
			(type default)
		)
	)
	(bus_entry
		(at 172.72 243.84)
		(size 1.27 1.27)
		(stroke
			(width 0)
			(type default)
		)
	)
	(bus_entry
		(at 64.77 104.14)
		(size 1.27 1.27)
		(stroke
			(width 0)
			(type default)
		)
	)
	(bus_entry
		(at 289.56 238.76)
		(size -1.27 1.27)
		(stroke
			(width 0)
			(type default)
		)
	)
	(bus_entry
		(at 232.41 45.72)
		(size 1.27 1.27)
		(stroke
			(width 0)
			(type default)
		)
	)
	(bus_entry
		(at 172.72 223.52)
		(size 1.27 1.27)
		(stroke
			(width 0)
			(type default)
		)
	)
	(bus_entry
		(at 252.73 185.42)
		(size -1.27 1.27)
		(stroke
			(width 0)
			(type default)
		)
	)
	(bus_entry
		(at 313.69 78.74)
		(size 1.27 1.27)
		(stroke
			(width 0)
			(type default)
		)
	)
	(bus_entry
		(at 130.81 58.42)
		(size -1.27 1.27)
		(stroke
			(width 0)
			(type default)
		)
	)
	(bus_entry
		(at 233.68 87.63)
		(size -1.27 -1.27)
		(stroke
			(width 0)
			(type default)
		)
	)
	(bus_entry
		(at 293.37 91.44)
		(size -1.27 1.27)
		(stroke
			(width 0)
			(type default)
		)
	)
	(bus_entry
		(at 196.85 193.04)
		(size 1.27 1.27)
		(stroke
			(width 0)
			(type default)
		)
	)
	(bus_entry
		(at 285.75 104.14)
		(size -1.27 1.27)
		(stroke
			(width 0)
			(type default)
		)
	)
	(bus_entry
		(at 128.27 81.28)
		(size -1.27 1.27)
		(stroke
			(width 0)
			(type default)
		)
	)
	(bus_entry
		(at 293.37 93.98)
		(size -1.27 1.27)
		(stroke
			(width 0)
			(type default)
		)
	)
	(bus_entry
		(at 288.29 81.28)
		(size -1.27 1.27)
		(stroke
			(width 0)
			(type default)
		)
	)
	(bus_entry
		(at 69.85 50.8)
		(size 1.27 1.27)
		(stroke
			(width 0)
			(type default)
		)
	)
	(bus_entry
		(at 69.85 58.42)
		(size 1.27 1.27)
		(stroke
			(width 0)
			(type default)
		)
	)
	(bus_entry
		(at 252.73 195.58)
		(size -1.27 1.27)
		(stroke
			(width 0)
			(type default)
		)
	)
	(bus_entry
		(at 232.41 93.98)
		(size 1.27 1.27)
		(stroke
			(width 0)
			(type default)
		)
	)
	(bus_entry
		(at 128.27 93.98)
		(size -1.27 1.27)
		(stroke
			(width 0)
			(type default)
		)
	)
	(bus_entry
		(at 313.69 66.04)
		(size 1.27 1.27)
		(stroke
			(width 0)
			(type default)
		)
	)
	(bus_entry
		(at 232.41 91.44)
		(size 1.27 1.27)
		(stroke
			(width 0)
			(type default)
		)
	)
	(bus_entry
		(at 289.56 228.6)
		(size -1.27 1.27)
		(stroke
			(width 0)
			(type default)
		)
	)
	(bus_entry
		(at 130.81 33.02)
		(size -1.27 1.27)
		(stroke
			(width 0)
			(type default)
		)
	)
	(bus_entry
		(at 369.57 60.96)
		(size -1.27 1.27)
		(stroke
			(width 0)
			(type default)
		)
	)
	(bus_entry
		(at 313.69 76.2)
		(size 1.27 1.27)
		(stroke
			(width 0)
			(type default)
		)
	)
	(bus_entry
		(at 69.85 68.58)
		(size 1.27 1.27)
		(stroke
			(width 0)
			(type default)
		)
	)
	(bus_entry
		(at 369.57 73.66)
		(size -1.27 1.27)
		(stroke
			(width 0)
			(type default)
		)
	)
	(wire
		(pts
			(xy 82.55 158.75) (xy 82.55 166.37)
		)
		(stroke
			(width 0)
			(type default)
		)
	)
	(wire
		(pts
			(xy 251.46 186.69) (xy 236.22 186.69)
		)
		(stroke
			(width 0)
			(type default)
		)
	)
	(bus
		(pts
			(xy 134.62 54.61) (xy 132.08 54.61)
		)
		(stroke
			(width 0)
			(type default)
		)
	)
	(wire
		(pts
			(xy 85.09 34.29) (xy 86.36 34.29)
		)
		(stroke
			(width 0)
			(type default)
		)
	)
	(wire
		(pts
			(xy 82.55 186.69) (xy 82.55 189.23)
		)
		(stroke
			(width 0)
			(type default)
		)
	)
	(wire
		(pts
			(xy 127 72.39) (xy 109.22 72.39)
		)
		(stroke
			(width 0)
			(type default)
		)
	)
	(wire
		(pts
			(xy 58.42 184.15) (xy 57.15 184.15)
		)
		(stroke
			(width 0)
			(type default)
		)
	)
	(wire
		(pts
			(xy 110.49 123.19) (xy 110.49 128.27)
		)
		(stroke
			(width 0)
			(type default)
		)
	)
	(wire
		(pts
			(xy 353.06 59.69) (xy 354.33 59.69)
		)
		(stroke
			(width 0)
			(type default)
		)
	)
	(wire
		(pts
			(xy 271.78 54.61) (xy 293.37 54.61)
		)
		(stroke
			(width 0)
			(type default)
		)
	)
	(wire
		(pts
			(xy 273.05 107.95) (xy 273.05 110.49)
		)
		(stroke
			(width 0)
			(type default)
		)
	)
	(bus
		(pts
			(xy 232.41 63.5) (xy 232.41 68.58)
		)
		(stroke
			(width 0)
			(type default)
		)
	)
	(wire
		(pts
			(xy 119.38 212.09) (xy 120.65 212.09)
		)
		(stroke
			(width 0)
			(type default)
		)
	)
	(wire
		(pts
			(xy 121.92 125.73) (xy 109.22 125.73)
		)
		(stroke
			(width 0)
			(type default)
		)
	)
	(wire
		(pts
			(xy 167.64 80.01) (xy 166.37 80.01)
		)
		(stroke
			(width 0)
			(type default)
		)
	)
	(wire
		(pts
			(xy 271.78 90.17) (xy 273.05 90.17)
		)
		(stroke
			(width 0)
			(type default)
		)
	)
	(wire
		(pts
			(xy 330.2 29.21) (xy 327.66 29.21)
		)
		(stroke
			(width 0)
			(type default)
		)
	)
	(wire
		(pts
			(xy 191.77 157.48) (xy 191.77 153.67)
		)
		(stroke
			(width 0)
			(type default)
		)
	)
	(wire
		(pts
			(xy 129.54 41.91) (xy 109.22 41.91)
		)
		(stroke
			(width 0)
			(type default)
		)
	)
	(wire
		(pts
			(xy 330.2 113.03) (xy 328.93 113.03)
		)
		(stroke
			(width 0)
			(type default)
		)
	)
	(wire
		(pts
			(xy 328.93 92.71) (xy 328.93 95.25)
		)
		(stroke
			(width 0)
			(type default)
		)
	)
	(wire
		(pts
			(xy 237.49 224.79) (xy 237.49 232.41)
		)
		(stroke
			(width 0)
			(type default)
		)
	)
	(bus
		(pts
			(xy 232.41 48.26) (xy 232.41 53.34)
		)
		(stroke
			(width 0)
			(type default)
		)
	)
	(bus
		(pts
			(xy 130.81 55.88) (xy 130.81 58.42)
		)
		(stroke
			(width 0)
			(type default)
		)
	)
	(bus
		(pts
			(xy 252.73 195.58) (xy 252.73 198.12)
		)
		(stroke
			(width 0)
			(type default)
		)
	)
	(wire
		(pts
			(xy 248.92 123.19) (xy 245.11 123.19)
		)
		(stroke
			(width 0)
			(type default)
		)
	)
	(wire
		(pts
			(xy 173.99 245.11) (xy 193.04 245.11)
		)
		(stroke
			(width 0)
			(type default)
		)
	)
	(wire
		(pts
			(xy 213.36 219.71) (xy 212.09 219.71)
		)
		(stroke
			(width 0)
			(type default)
		)
	)
	(wire
		(pts
			(xy 120.65 153.67) (xy 118.11 153.67)
		)
		(stroke
			(width 0)
			(type default)
		)
	)
	(wire
		(pts
			(xy 82.55 176.53) (xy 82.55 179.07)
		)
		(stroke
			(width 0)
			(type default)
		)
	)
	(wire
		(pts
			(xy 110.49 62.23) (xy 110.49 69.85)
		)
		(stroke
			(width 0)
			(type default)
		)
	)
	(wire
		(pts
			(xy 273.05 36.83) (xy 273.05 39.37)
		)
		(stroke
			(width 0)
			(type default)
		)
	)
	(wire
		(pts
			(xy 271.78 85.09) (xy 292.1 85.09)
		)
		(stroke
			(width 0)
			(type default)
		)
	)
	(wire
		(pts
			(xy 82.55 207.01) (xy 82.55 209.55)
		)
		(stroke
			(width 0)
			(type default)
		)
	)
	(wire
		(pts
			(xy 166.37 110.49) (xy 167.64 110.49)
		)
		(stroke
			(width 0)
			(type default)
		)
	)
	(bus
		(pts
			(xy 293.37 83.82) (xy 293.37 91.44)
		)
		(stroke
			(width 0)
			(type default)
		)
	)
	(wire
		(pts
			(xy 236.22 184.15) (xy 237.49 184.15)
		)
		(stroke
			(width 0)
			(type default)
		)
	)
	(wire
		(pts
			(xy 86.36 80.01) (xy 85.09 80.01)
		)
		(stroke
			(width 0)
			(type default)
		)
	)
	(wire
		(pts
			(xy 248.92 80.01) (xy 233.68 80.01)
		)
		(stroke
			(width 0)
			(type default)
		)
	)
	(wire
		(pts
			(xy 248.92 57.15) (xy 233.68 57.15)
		)
		(stroke
			(width 0)
			(type default)
		)
	)
	(wire
		(pts
			(xy 271.78 29.21) (xy 273.05 29.21)
		)
		(stroke
			(width 0)
			(type default)
		)
	)
	(wire
		(pts
			(xy 81.28 199.39) (xy 82.55 199.39)
		)
		(stroke
			(width 0)
			(type default)
		)
	)
	(wire
		(pts
			(xy 144.78 186.69) (xy 143.51 186.69)
		)
		(stroke
			(width 0)
			(type default)
		)
	)
	(wire
		(pts
			(xy 328.93 72.39) (xy 328.93 74.93)
		)
		(stroke
			(width 0)
			(type default)
		)
	)
	(wire
		(pts
			(xy 330.2 62.23) (xy 328.93 62.23)
		)
		(stroke
			(width 0)
			(type default)
		)
	)
	(bus
		(pts
			(xy 232.41 68.58) (xy 232.41 71.12)
		)
		(stroke
			(width 0)
			(type default)
		)
	)
	(wire
		(pts
			(xy 58.42 171.45) (xy 57.15 171.45)
		)
		(stroke
			(width 0)
			(type default)
		)
	)
	(bus
		(pts
			(xy 228.6 59.69) (xy 231.14 59.69)
		)
		(stroke
			(width 0)
			(type default)
		)
	)
	(wire
		(pts
			(xy 247.65 82.55) (xy 247.65 90.17)
		)
		(stroke
			(width 0)
			(type default)
		)
	)
	(wire
		(pts
			(xy 251.46 176.53) (xy 236.22 176.53)
		)
		(stroke
			(width 0)
			(type default)
		)
	)
	(wire
		(pts
			(xy 110.49 69.85) (xy 110.49 77.47)
		)
		(stroke
			(width 0)
			(type default)
		)
	)
	(wire
		(pts
			(xy 328.93 62.23) (xy 328.93 64.77)
		)
		(stroke
			(width 0)
			(type default)
		)
	)
	(wire
		(pts
			(xy 191.77 54.61) (xy 190.5 54.61)
		)
		(stroke
			(width 0)
			(type default)
		)
	)
	(wire
		(pts
			(xy 248.92 49.53) (xy 233.68 49.53)
		)
		(stroke
			(width 0)
			(type default)
		)
	)
	(wire
		(pts
			(xy 57.15 224.79) (xy 57.15 232.41)
		)
		(stroke
			(width 0)
			(type default)
		)
	)
	(wire
		(pts
			(xy 203.2 125.73) (xy 190.5 125.73)
		)
		(stroke
			(width 0)
			(type default)
		)
	)
	(wire
		(pts
			(xy 86.36 54.61) (xy 71.12 54.61)
		)
		(stroke
			(width 0)
			(type default)
		)
	)
	(wire
		(pts
			(xy 191.77 62.23) (xy 191.77 69.85)
		)
		(stroke
			(width 0)
			(type default)
		)
	)
	(wire
		(pts
			(xy 85.09 87.63) (xy 86.36 87.63)
		)
		(stroke
			(width 0)
			(type default)
		)
	)
	(wire
		(pts
			(xy 248.92 74.93) (xy 247.65 74.93)
		)
		(stroke
			(width 0)
			(type default)
		)
	)
	(wire
		(pts
			(xy 72.39 30.48) (xy 72.39 31.75)
		)
		(stroke
			(width 0)
			(type default)
		)
	)
	(wire
		(pts
			(xy 248.92 107.95) (xy 236.22 107.95)
		)
		(stroke
			(width 0)
			(type default)
		)
	)
	(wire
		(pts
			(xy 273.05 29.21) (xy 273.05 36.83)
		)
		(stroke
			(width 0)
			(type default)
		)
	)
	(wire
		(pts
			(xy 273.05 59.69) (xy 273.05 67.31)
		)
		(stroke
			(width 0)
			(type default)
		)
	)
	(wire
		(pts
			(xy 85.09 64.77) (xy 85.09 72.39)
		)
		(stroke
			(width 0)
			(type default)
		)
	)
	(wire
		(pts
			(xy 72.39 31.75) (xy 68.58 31.75)
		)
		(stroke
			(width 0)
			(type default)
		)
	)
	(wire
		(pts
			(xy 353.06 107.95) (xy 354.33 107.95)
		)
		(stroke
			(width 0)
			(type default)
		)
	)
	(wire
		(pts
			(xy 191.77 69.85) (xy 190.5 69.85)
		)
		(stroke
			(width 0)
			(type default)
		)
	)
	(wire
		(pts
			(xy 210.82 245.11) (xy 213.36 245.11)
		)
		(stroke
			(width 0)
			(type default)
		)
	)
	(wire
		(pts
			(xy 387.35 226.06) (xy 397.51 226.06)
		)
		(stroke
			(width 0)
			(type default)
		)
	)
	(bus
		(pts
			(xy 232.41 76.2) (xy 231.14 74.93)
		)
		(stroke
			(width 0)
			(type default)
		)
	)
	(wire
		(pts
			(xy 166.37 72.39) (xy 166.37 80.01)
		)
		(stroke
			(width 0)
			(type default)
		)
	)
	(bus
		(pts
			(xy 64.77 88.9) (xy 64.77 91.44)
		)
		(stroke
			(width 0)
			(type default)
		)
	)
	(wire
		(pts
			(xy 57.15 204.47) (xy 57.15 212.09)
		)
		(stroke
			(width 0)
			(type default)
		)
	)
	(wire
		(pts
			(xy 237.49 163.83) (xy 237.49 171.45)
		)
		(stroke
			(width 0)
			(type default)
		)
	)
	(wire
		(pts
			(xy 212.09 168.91) (xy 212.09 176.53)
		)
		(stroke
			(width 0)
			(type default)
		)
	)
	(wire
		(pts
			(xy 353.06 67.31) (xy 354.33 67.31)
		)
		(stroke
			(width 0)
			(type default)
		)
	)
	(bus
		(pts
			(xy 252.73 185.42) (xy 252.73 187.96)
		)
		(stroke
			(width 0)
			(type default)
		)
	)
	(bus
		(pts
			(xy 369.57 71.12) (xy 369.57 73.66)
		)
		(stroke
			(width 0)
			(type default)
		)
	)
	(wire
		(pts
			(xy 248.92 64.77) (xy 233.68 64.77)
		)
		(stroke
			(width 0)
			(type default)
		)
	)
	(wire
		(pts
			(xy 236.22 234.95) (xy 237.49 234.95)
		)
		(stroke
			(width 0)
			(type default)
		)
	)
	(wire
		(pts
			(xy 271.78 97.79) (xy 273.05 97.79)
		)
		(stroke
			(width 0)
			(type default)
		)
	)
	(bus
		(pts
			(xy 252.73 187.96) (xy 252.73 195.58)
		)
		(stroke
			(width 0)
			(type default)
		)
	)
	(bus
		(pts
			(xy 228.6 74.93) (xy 231.14 74.93)
		)
		(stroke
			(width 0)
			(type default)
		)
	)
	(bus
		(pts
			(xy 369.57 53.34) (xy 369.57 60.96)
		)
		(stroke
			(width 0)
			(type default)
		)
	)
	(wire
		(pts
			(xy 129.54 44.45) (xy 109.22 44.45)
		)
		(stroke
			(width 0)
			(type default)
		)
	)
	(wire
		(pts
			(xy 212.09 240.03) (xy 212.09 247.65)
		)
		(stroke
			(width 0)
			(type default)
		)
	)
	(wire
		(pts
			(xy 237.49 242.57) (xy 237.49 245.11)
		)
		(stroke
			(width 0)
			(type default)
		)
	)
	(bus
		(pts
			(xy 232.41 45.72) (xy 232.41 48.26)
		)
		(stroke
			(width 0)
			(type default)
		)
	)
	(wire
		(pts
			(xy 241.3 217.17) (xy 238.76 219.71)
		)
		(stroke
			(width 0)
			(type default)
		)
	)
	(wire
		(pts
			(xy 166.37 102.87) (xy 166.37 110.49)
		)
		(stroke
			(width 0)
			(type default)
		)
	)
	(wire
		(pts
			(xy 199.39 252.73) (xy 213.36 252.73)
		)
		(stroke
			(width 0)
			(type default)
		)
	)
	(bus
		(pts
			(xy 294.64 60.96) (xy 294.64 63.5)
		)
		(stroke
			(width 0)
			(type default)
		)
	)
	(wire
		(pts
			(xy 110.49 62.23) (xy 109.22 62.23)
		)
		(stroke
			(width 0)
			(type default)
		)
	)
	(wire
		(pts
			(xy 85.09 57.15) (xy 85.09 64.77)
		)
		(stroke
			(width 0)
			(type default)
		)
	)
	(wire
		(pts
			(xy 213.36 217.17) (xy 212.09 217.17)
		)
		(stroke
			(width 0)
			(type default)
		)
	)
	(bus
		(pts
			(xy 311.15 34.29) (xy 312.42 34.29)
		)
		(stroke
			(width 0)
			(type default)
		)
	)
	(wire
		(pts
			(xy 314.96 80.01) (xy 330.2 80.01)
		)
		(stroke
			(width 0)
			(type default)
		)
	)
	(wire
		(pts
			(xy 328.93 85.09) (xy 328.93 92.71)
		)
		(stroke
			(width 0)
			(type default)
		)
	)
	(wire
		(pts
			(xy 248.92 41.91) (xy 247.65 41.91)
		)
		(stroke
			(width 0)
			(type default)
		)
	)
	(wire
		(pts
			(xy 248.92 125.73) (xy 247.65 125.73)
		)
		(stroke
			(width 0)
			(type default)
		)
	)
	(wire
		(pts
			(xy 166.37 87.63) (xy 166.37 95.25)
		)
		(stroke
			(width 0)
			(type default)
		)
	)
	(wire
		(pts
			(xy 110.49 115.57) (xy 110.49 123.19)
		)
		(stroke
			(width 0)
			(type default)
		)
	)
	(wire
		(pts
			(xy 166.37 102.87) (xy 167.64 102.87)
		)
		(stroke
			(width 0)
			(type default)
		)
	)
	(wire
		(pts
			(xy 57.15 201.93) (xy 57.15 204.47)
		)
		(stroke
			(width 0)
			(type default)
		)
	)
	(wire
		(pts
			(xy 236.22 242.57) (xy 237.49 242.57)
		)
		(stroke
			(width 0)
			(type default)
		)
	)
	(wire
		(pts
			(xy 236.22 212.09) (xy 237.49 212.09)
		)
		(stroke
			(width 0)
			(type default)
		)
	)
	(wire
		(pts
			(xy 247.65 44.45) (xy 247.65 52.07)
		)
		(stroke
			(width 0)
			(type default)
		)
	)
	(wire
		(pts
			(xy 237.49 153.67) (xy 237.49 161.29)
		)
		(stroke
			(width 0)
			(type default)
		)
	)
	(bus
		(pts
			(xy 128.27 96.52) (xy 128.27 101.6)
		)
		(stroke
			(width 0)
			(type default)
		)
	)
	(wire
		(pts
			(xy 166.37 57.15) (xy 167.64 57.15)
		)
		(stroke
			(width 0)
			(type default)
		)
	)
	(bus
		(pts
			(xy 66.04 64.77) (xy 68.58 64.77)
		)
		(stroke
			(width 0)
			(type default)
		)
	)
	(bus
		(pts
			(xy 196.85 182.88) (xy 196.85 190.5)
		)
		(stroke
			(width 0)
			(type default)
		)
	)
	(wire
		(pts
			(xy 248.92 97.79) (xy 247.65 97.79)
		)
		(stroke
			(width 0)
			(type default)
		)
	)
	(wire
		(pts
			(xy 273.05 39.37) (xy 273.05 46.99)
		)
		(stroke
			(width 0)
			(type default)
		)
	)
	(bus
		(pts
			(xy 289.56 204.47) (xy 289.56 205.74)
		)
		(stroke
			(width 0)
			(type default)
		)
	)
	(bus
		(pts
			(xy 128.27 71.12) (xy 128.27 73.66)
		)
		(stroke
			(width 0)
			(type default)
		)
	)
	(wire
		(pts
			(xy 166.37 31.75) (xy 167.64 31.75)
		)
		(stroke
			(width 0)
			(type default)
		)
	)
	(wire
		(pts
			(xy 330.2 49.53) (xy 314.96 49.53)
		)
		(stroke
			(width 0)
			(type default)
		)
	)
	(wire
		(pts
			(xy 166.37 34.29) (xy 167.64 34.29)
		)
		(stroke
			(width 0)
			(type default)
		)
	)
	(bus
		(pts
			(xy 68.58 49.53) (xy 69.85 50.8)
		)
		(stroke
			(width 0)
			(type default)
		)
	)
	(wire
		(pts
			(xy 212.09 186.69) (xy 212.09 189.23)
		)
		(stroke
			(width 0)
			(type default)
		)
	)
	(wire
		(pts
			(xy 120.65 204.47) (xy 119.38 204.47)
		)
		(stroke
			(width 0)
			(type default)
		)
	)
	(wire
		(pts
			(xy 236.22 209.55) (xy 288.29 209.55)
		)
		(stroke
			(width 0)
			(type default)
		)
	)
	(bus
		(pts
			(xy 369.57 33.02) (xy 369.57 40.64)
		)
		(stroke
			(width 0)
			(type default)
		)
	)
	(bus
		(pts
			(xy 290.83 203.2) (xy 289.56 204.47)
		)
		(stroke
			(width 0)
			(type default)
		)
	)
	(wire
		(pts
			(xy 57.15 191.77) (xy 57.15 194.31)
		)
		(stroke
			(width 0)
			(type default)
		)
	)
	(wire
		(pts
			(xy 85.09 87.63) (xy 85.09 95.25)
		)
		(stroke
			(width 0)
			(type default)
		)
	)
	(bus
		(pts
			(xy 289.56 208.28) (xy 289.56 215.9)
		)
		(stroke
			(width 0)
			(type default)
		)
	)
	(wire
		(pts
			(xy 247.65 41.91) (xy 247.65 44.45)
		)
		(stroke
			(width 0)
			(type default)
		)
	)
	(wire
		(pts
			(xy 191.77 29.21) (xy 191.77 36.83)
		)
		(stroke
			(width 0)
			(type default)
		)
	)
	(wire
		(pts
			(xy 173.99 222.25) (xy 189.23 222.25)
		)
		(stroke
			(width 0)
			(type default)
		)
	)
	(wire
		(pts
			(xy 354.33 107.95) (xy 354.33 110.49)
		)
		(stroke
			(width 0)
			(type default)
		)
	)
	(wire
		(pts
			(xy 314.96 77.47) (xy 330.2 77.47)
		)
		(stroke
			(width 0)
			(type default)
		)
	)
	(wire
		(pts
			(xy 328.93 113.03) (xy 328.93 115.57)
		)
		(stroke
			(width 0)
			(type default)
		)
	)
	(wire
		(pts
			(xy 213.36 166.37) (xy 212.09 166.37)
		)
		(stroke
			(width 0)
			(type default)
		)
	)
	(bus
		(pts
			(xy 313.69 38.1) (xy 313.69 45.72)
		)
		(stroke
			(width 0)
			(type default)
		)
	)
	(wire
		(pts
			(xy 354.33 36.83) (xy 354.33 39.37)
		)
		(stroke
			(width 0)
			(type default)
		)
	)
	(bus
		(pts
			(xy 289.56 228.6) (xy 289.56 236.22)
		)
		(stroke
			(width 0)
			(type default)
		)
	)
	(wire
		(pts
			(xy 328.93 123.19) (xy 328.93 125.73)
		)
		(stroke
			(width 0)
			(type default)
		)
	)
	(wire
		(pts
			(xy 393.7 180.34) (xy 393.7 185.42)
		)
		(stroke
			(width 0)
			(type default)
		)
	)
	(wire
		(pts
			(xy 350.52 181.61) (xy 353.06 181.61)
		)
		(stroke
			(width 0)
			(type default)
		)
	)
	(wire
		(pts
			(xy 85.09 125.73) (xy 85.09 129.54)
		)
		(stroke
			(width 0)
			(type default)
		)
	)
	(wire
		(pts
			(xy 212.09 237.49) (xy 212.09 240.03)
		)
		(stroke
			(width 0)
			(type default)
		)
	)
	(wire
		(pts
			(xy 82.55 227.33) (xy 82.55 229.87)
		)
		(stroke
			(width 0)
			(type default)
		)
	)
	(wire
		(pts
			(xy 248.92 115.57) (xy 236.22 115.57)
		)
		(stroke
			(width 0)
			(type default)
		)
	)
	(wire
		(pts
			(xy 82.55 229.87) (xy 82.55 237.49)
		)
		(stroke
			(width 0)
			(type default)
		)
	)
	(wire
		(pts
			(xy 285.75 125.73) (xy 271.78 125.73)
		)
		(stroke
			(width 0)
			(type default)
		)
	)
	(wire
		(pts
			(xy 82.55 250.19) (xy 81.28 250.19)
		)
		(stroke
			(width 0)
			(type default)
		)
	)
	(wire
		(pts
			(xy 119.38 250.19) (xy 119.38 254)
		)
		(stroke
			(width 0)
			(type default)
		)
	)
	(wire
		(pts
			(xy 97.79 242.57) (xy 86.36 242.57)
		)
		(stroke
			(width 0)
			(type default)
		)
	)
	(wire
		(pts
			(xy 127 102.87) (xy 109.22 102.87)
		)
		(stroke
			(width 0)
			(type default)
		)
	)
	(wire
		(pts
			(xy 271.78 69.85) (xy 273.05 69.85)
		)
		(stroke
			(width 0)
			(type default)
		)
	)
	(wire
		(pts
			(xy 339.09 241.3) (xy 339.09 238.76)
		)
		(stroke
			(width 0)
			(type default)
		)
	)
	(wire
		(pts
			(xy 173.99 242.57) (xy 189.23 242.57)
		)
		(stroke
			(width 0)
			(type default)
		)
	)
	(wire
		(pts
			(xy 191.77 54.61) (xy 191.77 62.23)
		)
		(stroke
			(width 0)
			(type default)
		)
	)
	(wire
		(pts
			(xy 71.12 52.07) (xy 86.36 52.07)
		)
		(stroke
			(width 0)
			(type default)
		)
	)
	(wire
		(pts
			(xy 273.05 123.19) (xy 273.05 128.27)
		)
		(stroke
			(width 0)
			(type default)
		)
	)
	(wire
		(pts
			(xy 328.93 102.87) (xy 328.93 105.41)
		)
		(stroke
			(width 0)
			(type default)
		)
	)
	(wire
		(pts
			(xy 66.04 85.09) (xy 86.36 85.09)
		)
		(stroke
			(width 0)
			(type default)
		)
	)
	(bus
		(pts
			(xy 369.57 63.5) (xy 369.57 71.12)
		)
		(stroke
			(width 0)
			(type default)
		)
	)
	(wire
		(pts
			(xy 330.2 39.37) (xy 314.96 39.37)
		)
		(stroke
			(width 0)
			(type default)
		)
	)
	(wire
		(pts
			(xy 109.22 85.09) (xy 110.49 85.09)
		)
		(stroke
			(width 0)
			(type default)
		)
	)
	(bus
		(pts
			(xy 232.41 60.96) (xy 232.41 63.5)
		)
		(stroke
			(width 0)
			(type default)
		)
	)
	(wire
		(pts
			(xy 212.09 196.85) (xy 212.09 199.39)
		)
		(stroke
			(width 0)
			(type default)
		)
	)
	(wire
		(pts
			(xy 236.22 161.29) (xy 237.49 161.29)
		)
		(stroke
			(width 0)
			(type default)
		)
	)
	(wire
		(pts
			(xy 330.2 74.93) (xy 328.93 74.93)
		)
		(stroke
			(width 0)
			(type default)
		)
	)
	(wire
		(pts
			(xy 247.65 59.69) (xy 247.65 67.31)
		)
		(stroke
			(width 0)
			(type default)
		)
	)
	(wire
		(pts
			(xy 238.76 219.71) (xy 236.22 219.71)
		)
		(stroke
			(width 0)
			(type default)
		)
	)
	(wire
		(pts
			(xy 256.54 250.19) (xy 236.22 250.19)
		)
		(stroke
			(width 0)
			(type default)
		)
	)
	(wire
		(pts
			(xy 314.96 67.31) (xy 330.2 67.31)
		)
		(stroke
			(width 0)
			(type default)
		)
	)
	(wire
		(pts
			(xy 237.49 184.15) (xy 237.49 191.77)
		)
		(stroke
			(width 0)
			(type default)
		)
	)
	(wire
		(pts
			(xy 382.27 236.22) (xy 379.73 236.22)
		)
		(stroke
			(width 0)
			(type default)
		)
	)
	(wire
		(pts
			(xy 86.36 97.79) (xy 66.04 97.79)
		)
		(stroke
			(width 0)
			(type default)
		)
	)
	(bus
		(pts
			(xy 313.69 66.04) (xy 313.69 68.58)
		)
		(stroke
			(width 0)
			(type default)
		)
	)
	(wire
		(pts
			(xy 334.01 187.96) (xy 334.01 189.23)
		)
		(stroke
			(width 0)
			(type default)
		)
	)
	(wire
		(pts
			(xy 236.22 201.93) (xy 237.49 201.93)
		)
		(stroke
			(width 0)
			(type default)
		)
	)
	(wire
		(pts
			(xy 368.3 44.45) (xy 353.06 44.45)
		)
		(stroke
			(width 0)
			(type default)
		)
	)
	(wire
		(pts
			(xy 110.49 107.95) (xy 109.22 107.95)
		)
		(stroke
			(width 0)
			(type default)
		)
	)
	(wire
		(pts
			(xy 328.93 125.73) (xy 328.93 129.54)
		)
		(stroke
			(width 0)
			(type default)
		)
	)
	(wire
		(pts
			(xy 86.36 245.11) (xy 86.36 242.57)
		)
		(stroke
			(width 0)
			(type default)
		)
	)
	(wire
		(pts
			(xy 57.15 184.15) (xy 57.15 191.77)
		)
		(stroke
			(width 0)
			(type default)
		)
	)
	(wire
		(pts
			(xy 353.06 39.37) (xy 354.33 39.37)
		)
		(stroke
			(width 0)
			(type default)
		)
	)
	(bus
		(pts
			(xy 60.96 71.12) (xy 63.5 71.12)
		)
		(stroke
			(width 0)
			(type default)
		)
	)
	(wire
		(pts
			(xy 57.15 161.29) (xy 57.15 163.83)
		)
		(stroke
			(width 0)
			(type default)
		)
	)
	(wire
		(pts
			(xy 143.51 153.67) (xy 144.78 153.67)
		)
		(stroke
			(width 0)
			(type default)
		)
	)
	(wire
		(pts
			(xy 248.92 120.65) (xy 247.65 120.65)
		)
		(stroke
			(width 0)
			(type default)
		)
	)
	(bus
		(pts
			(xy 134.62 29.21) (xy 132.08 29.21)
		)
		(stroke
			(width 0)
			(type default)
		)
	)
	(wire
		(pts
			(xy 271.78 95.25) (xy 292.1 95.25)
		)
		(stroke
			(width 0)
			(type default)
		)
	)
	(wire
		(pts
			(xy 271.78 62.23) (xy 293.37 62.23)
		)
		(stroke
			(width 0)
			(type default)
		)
	)
	(wire
		(pts
			(xy 248.92 118.11) (xy 245.11 118.11)
		)
		(stroke
			(width 0)
			(type default)
		)
	)
	(wire
		(pts
			(xy 354.33 120.65) (xy 354.33 128.27)
		)
		(stroke
			(width 0)
			(type default)
		)
	)
	(wire
		(pts
			(xy 358.14 176.53) (xy 368.3 176.53)
		)
		(stroke
			(width 0)
			(type default)
		)
	)
	(wire
		(pts
			(xy 339.09 228.6) (xy 349.25 228.6)
		)
		(stroke
			(width 0)
			(type default)
		)
	)
	(wire
		(pts
			(xy 275.59 115.57) (xy 275.59 120.65)
		)
		(stroke
			(width 0)
			(type default)
		)
	)
	(wire
		(pts
			(xy 247.65 125.73) (xy 247.65 129.54)
		)
		(stroke
			(width 0)
			(type default)
		)
	)
	(wire
		(pts
			(xy 198.12 194.31) (xy 213.36 194.31)
		)
		(stroke
			(width 0)
			(type default)
		)
	)
	(wire
		(pts
			(xy 270.51 250.19) (xy 261.62 250.19)
		)
		(stroke
			(width 0)
			(type default)
		)
	)
	(wire
		(pts
			(xy 110.49 85.09) (xy 110.49 92.71)
		)
		(stroke
			(width 0)
			(type default)
		)
	)
	(wire
		(pts
			(xy 119.38 204.47) (xy 119.38 212.09)
		)
		(stroke
			(width 0)
			(type default)
		)
	)
	(wire
		(pts
			(xy 119.38 181.61) (xy 120.65 181.61)
		)
		(stroke
			(width 0)
			(type default)
		)
	)
	(wire
		(pts
			(xy 241.3 237.49) (xy 238.76 240.03)
		)
		(stroke
			(width 0)
			(type default)
		)
	)
	(wire
		(pts
			(xy 339.09 231.14) (xy 339.09 228.6)
		)
		(stroke
			(width 0)
			(type default)
		)
	)
	(wire
		(pts
			(xy 85.09 95.25) (xy 85.09 102.87)
		)
		(stroke
			(width 0)
			(type default)
		)
	)
	(bus
		(pts
			(xy 289.56 215.9) (xy 289.56 218.44)
		)
		(stroke
			(width 0)
			(type default)
		)
	)
	(wire
		(pts
			(xy 350.52 176.53) (xy 358.14 176.53)
		)
		(stroke
			(width 0)
			(type default)
		)
	)
	(wire
		(pts
			(xy 81.28 232.41) (xy 83.82 232.41)
		)
		(stroke
			(width 0)
			(type default)
		)
	)
	(wire
		(pts
			(xy 191.77 39.37) (xy 191.77 46.99)
		)
		(stroke
			(width 0)
			(type default)
		)
	)
	(wire
		(pts
			(xy 236.22 245.11) (xy 237.49 245.11)
		)
		(stroke
			(width 0)
			(type default)
		)
	)
	(wire
		(pts
			(xy 273.05 80.01) (xy 273.05 87.63)
		)
		(stroke
			(width 0)
			(type default)
		)
	)
	(wire
		(pts
			(xy 119.38 219.71) (xy 120.65 219.71)
		)
		(stroke
			(width 0)
			(type default)
		)
	)
	(wire
		(pts
			(xy 203.2 125.73) (xy 203.2 127)
		)
		(stroke
			(width 0)
			(type default)
		)
	)
	(wire
		(pts
			(xy 127 87.63) (xy 109.22 87.63)
		)
		(stroke
			(width 0)
			(type default)
		)
	)
	(wire
		(pts
			(xy 236.22 207.01) (xy 288.29 207.01)
		)
		(stroke
			(width 0)
			(type default)
		)
	)
	(wire
		(pts
			(xy 58.42 163.83) (xy 57.15 163.83)
		)
		(stroke
			(width 0)
			(type default)
		)
	)
	(wire
		(pts
			(xy 190.5 85.09) (xy 191.77 85.09)
		)
		(stroke
			(width 0)
			(type default)
		)
	)
	(wire
		(pts
			(xy 326.39 179.07) (xy 335.28 179.07)
		)
		(stroke
			(width 0)
			(type default)
		)
	)
	(bus
		(pts
			(xy 64.77 83.82) (xy 64.77 88.9)
		)
		(stroke
			(width 0)
			(type default)
		)
	)
	(wire
		(pts
			(xy 353.06 77.47) (xy 354.33 77.47)
		)
		(stroke
			(width 0)
			(type default)
		)
	)
	(wire
		(pts
			(xy 85.09 41.91) (xy 85.09 49.53)
		)
		(stroke
			(width 0)
			(type default)
		)
	)
	(wire
		(pts
			(xy 57.15 153.67) (xy 57.15 161.29)
		)
		(stroke
			(width 0)
			(type default)
		)
	)
	(wire
		(pts
			(xy 144.78 153.67) (xy 144.78 161.29)
		)
		(stroke
			(width 0)
			(type default)
		)
	)
	(wire
		(pts
			(xy 330.2 41.91) (xy 328.93 41.91)
		)
		(stroke
			(width 0)
			(type default)
		)
	)
	(wire
		(pts
			(xy 237.49 161.29) (xy 237.49 163.83)
		)
		(stroke
			(width 0)
			(type default)
		)
	)
	(wire
		(pts
			(xy 85.09 49.53) (xy 86.36 49.53)
		)
		(stroke
			(width 0)
			(type default)
		)
	)
	(wire
		(pts
			(xy 353.06 97.79) (xy 354.33 97.79)
		)
		(stroke
			(width 0)
			(type default)
		)
	)
	(wire
		(pts
			(xy 81.28 237.49) (xy 82.55 237.49)
		)
		(stroke
			(width 0)
			(type default)
		)
	)
	(wire
		(pts
			(xy 377.19 185.42) (xy 384.81 185.42)
		)
		(stroke
			(width 0)
			(type default)
		)
	)
	(wire
		(pts
			(xy 237.49 181.61) (xy 237.49 184.15)
		)
		(stroke
			(width 0)
			(type default)
		)
	)
	(wire
		(pts
			(xy 85.09 49.53) (xy 85.09 57.15)
		)
		(stroke
			(width 0)
			(type default)
		)
	)
	(bus
		(pts
			(xy 285.75 101.6) (xy 285.75 104.14)
		)
		(stroke
			(width 0)
			(type default)
		)
	)
	(wire
		(pts
			(xy 233.68 87.63) (xy 248.92 87.63)
		)
		(stroke
			(width 0)
			(type default)
		)
	)
	(wire
		(pts
			(xy 144.78 201.93) (xy 144.78 209.55)
		)
		(stroke
			(width 0)
			(type default)
		)
	)
	(wire
		(pts
			(xy 354.33 80.01) (xy 354.33 87.63)
		)
		(stroke
			(width 0)
			(type default)
		)
	)
	(wire
		(pts
			(xy 273.05 97.79) (xy 273.05 100.33)
		)
		(stroke
			(width 0)
			(type default)
		)
	)
	(wire
		(pts
			(xy 85.09 102.87) (xy 85.09 110.49)
		)
		(stroke
			(width 0)
			(type default)
		)
	)
	(wire
		(pts
			(xy 387.35 246.38) (xy 397.51 246.38)
		)
		(stroke
			(width 0)
			(type default)
		)
	)
	(wire
		(pts
			(xy 144.78 232.41) (xy 143.51 232.41)
		)
		(stroke
			(width 0)
			(type default)
		)
	)
	(wire
		(pts
			(xy 248.92 77.47) (xy 233.68 77.47)
		)
		(stroke
			(width 0)
			(type default)
		)
	)
	(wire
		(pts
			(xy 212.09 219.71) (xy 212.09 227.33)
		)
		(stroke
			(width 0)
			(type default)
		)
	)
	(bus
		(pts
			(xy 170.18 219.71) (xy 171.45 219.71)
		)
		(stroke
			(width 0)
			(type default)
		)
	)
	(wire
		(pts
			(xy 57.15 252.73) (xy 58.42 252.73)
		)
		(stroke
			(width 0)
			(type default)
		)
	)
	(wire
		(pts
			(xy 119.38 156.21) (xy 119.38 158.75)
		)
		(stroke
			(width 0)
			(type default)
		)
	)
	(wire
		(pts
			(xy 328.93 44.45) (xy 328.93 52.07)
		)
		(stroke
			(width 0)
			(type default)
		)
	)
	(wire
		(pts
			(xy 208.28 234.95) (xy 210.82 232.41)
		)
		(stroke
			(width 0)
			(type default)
		)
	)
	(wire
		(pts
			(xy 166.37 95.25) (xy 166.37 102.87)
		)
		(stroke
			(width 0)
			(type default)
		)
	)
	(wire
		(pts
			(xy 288.29 250.19) (xy 273.05 250.19)
		)
		(stroke
			(width 0)
			(type default)
		)
	)
	(wire
		(pts
			(xy 350.52 187.96) (xy 353.06 187.96)
		)
		(stroke
			(width 0)
			(type default)
		)
	)
	(wire
		(pts
			(xy 237.49 232.41) (xy 237.49 234.95)
		)
		(stroke
			(width 0)
			(type default)
		)
	)
	(wire
		(pts
			(xy 58.42 204.47) (xy 57.15 204.47)
		)
		(stroke
			(width 0)
			(type default)
		)
	)
	(wire
		(pts
			(xy 129.54 57.15) (xy 109.22 57.15)
		)
		(stroke
			(width 0)
			(type default)
		)
	)
	(wire
		(pts
			(xy 85.09 72.39) (xy 85.09 80.01)
		)
		(stroke
			(width 0)
			(type default)
		)
	)
	(wire
		(pts
			(xy 110.49 36.83) (xy 109.22 36.83)
		)
		(stroke
			(width 0)
			(type default)
		)
	)
	(bus
		(pts
			(xy 62.23 95.25) (xy 63.5 95.25)
		)
		(stroke
			(width 0)
			(type default)
		)
	)
	(bus
		(pts
			(xy 63.5 71.12) (xy 64.77 72.39)
		)
		(stroke
			(width 0)
			(type default)
		)
	)
	(wire
		(pts
			(xy 330.2 95.25) (xy 328.93 95.25)
		)
		(stroke
			(width 0)
			(type default)
		)
	)
	(wire
		(pts
			(xy 191.77 107.95) (xy 190.5 107.95)
		)
		(stroke
			(width 0)
			(type default)
		)
	)
	(wire
		(pts
			(xy 354.33 69.85) (xy 354.33 77.47)
		)
		(stroke
			(width 0)
			(type default)
		)
	)
	(wire
		(pts
			(xy 119.38 227.33) (xy 120.65 227.33)
		)
		(stroke
			(width 0)
			(type default)
		)
	)
	(wire
		(pts
			(xy 110.49 69.85) (xy 109.22 69.85)
		)
		(stroke
			(width 0)
			(type default)
		)
	)
	(wire
		(pts
			(xy 236.22 171.45) (xy 237.49 171.45)
		)
		(stroke
			(width 0)
			(type default)
		)
	)
	(wire
		(pts
			(xy 330.2 64.77) (xy 328.93 64.77)
		)
		(stroke
			(width 0)
			(type default)
		)
	)
	(wire
		(pts
			(xy 166.37 57.15) (xy 166.37 64.77)
		)
		(stroke
			(width 0)
			(type default)
		)
	)
	(wire
		(pts
			(xy 237.49 212.09) (xy 237.49 214.63)
		)
		(stroke
			(width 0)
			(type default)
		)
	)
	(wire
		(pts
			(xy 129.54 52.07) (xy 109.22 52.07)
		)
		(stroke
			(width 0)
			(type default)
		)
	)
	(wire
		(pts
			(xy 337.82 226.06) (xy 358.14 226.06)
		)
		(stroke
			(width 0)
			(type default)
		)
	)
	(wire
		(pts
			(xy 273.05 49.53) (xy 273.05 57.15)
		)
		(stroke
			(width 0)
			(type default)
		)
	)
	(wire
		(pts
			(xy 237.49 234.95) (xy 237.49 242.57)
		)
		(stroke
			(width 0)
			(type default)
		)
	)
	(wire
		(pts
			(xy 339.09 236.22) (xy 339.09 233.68)
		)
		(stroke
			(width 0)
			(type default)
		)
	)
	(bus
		(pts
			(xy 287.02 100.33) (xy 285.75 101.6)
		)
		(stroke
			(width 0)
			(type default)
		)
	)
	(wire
		(pts
			(xy 241.3 229.87) (xy 238.76 227.33)
		)
		(stroke
			(width 0)
			(type default)
		)
	)
	(wire
		(pts
			(xy 119.38 173.99) (xy 120.65 173.99)
		)
		(stroke
			(width 0)
			(type default)
		)
	)
	(wire
		(pts
			(xy 368.3 54.61) (xy 353.06 54.61)
		)
		(stroke
			(width 0)
			(type default)
		)
	)
	(wire
		(pts
			(xy 328.93 185.42) (xy 335.28 185.42)
		)
		(stroke
			(width 0)
			(type default)
		)
	)
	(wire
		(pts
			(xy 57.15 171.45) (xy 57.15 173.99)
		)
		(stroke
			(width 0)
			(type default)
		)
	)
	(wire
		(pts
			(xy 237.49 214.63) (xy 237.49 222.25)
		)
		(stroke
			(width 0)
			(type default)
		)
	)
	(wire
		(pts
			(xy 330.2 34.29) (xy 328.93 34.29)
		)
		(stroke
			(width 0)
			(type default)
		)
	)
	(wire
		(pts
			(xy 191.77 85.09) (xy 191.77 92.71)
		)
		(stroke
			(width 0)
			(type default)
		)
	)
	(wire
		(pts
			(xy 66.04 77.47) (xy 86.36 77.47)
		)
		(stroke
			(width 0)
			(type default)
		)
	)
	(wire
		(pts
			(xy 119.38 158.75) (xy 119.38 166.37)
		)
		(stroke
			(width 0)
			(type default)
		)
	)
	(wire
		(pts
			(xy 119.38 234.95) (xy 119.38 242.57)
		)
		(stroke
			(width 0)
			(type default)
		)
	)
	(wire
		(pts
			(xy 379.73 226.06) (xy 379.73 224.79)
		)
		(stroke
			(width 0)
			(type default)
		)
	)
	(wire
		(pts
			(xy 144.78 247.65) (xy 144.78 252.73)
		)
		(stroke
			(width 0)
			(type default)
		)
	)
	(bus
		(pts
			(xy 293.37 91.44) (xy 293.37 93.98)
		)
		(stroke
			(width 0)
			(type default)
		)
	)
	(wire
		(pts
			(xy 167.64 128.27) (xy 152.4 128.27)
		)
		(stroke
			(width 0)
			(type default)
		)
	)
	(wire
		(pts
			(xy 191.77 46.99) (xy 190.5 46.99)
		)
		(stroke
			(width 0)
			(type default)
		)
	)
	(wire
		(pts
			(xy 379.73 215.9) (xy 379.73 214.63)
		)
		(stroke
			(width 0)
			(type default)
		)
	)
	(wire
		(pts
			(xy 330.2 46.99) (xy 314.96 46.99)
		)
		(stroke
			(width 0)
			(type default)
		)
	)
	(wire
		(pts
			(xy 110.49 123.19) (xy 109.22 123.19)
		)
		(stroke
			(width 0)
			(type default)
		)
	)
	(wire
		(pts
			(xy 330.2 82.55) (xy 328.93 82.55)
		)
		(stroke
			(width 0)
			(type default)
		)
	)
	(wire
		(pts
			(xy 271.78 87.63) (xy 273.05 87.63)
		)
		(stroke
			(width 0)
			(type default)
		)
	)
	(wire
		(pts
			(xy 58.42 212.09) (xy 57.15 212.09)
		)
		(stroke
			(width 0)
			(type default)
		)
	)
	(wire
		(pts
			(xy 127 80.01) (xy 109.22 80.01)
		)
		(stroke
			(width 0)
			(type default)
		)
	)
	(wire
		(pts
			(xy 368.3 52.07) (xy 353.06 52.07)
		)
		(stroke
			(width 0)
			(type default)
		)
	)
	(wire
		(pts
			(xy 129.54 31.75) (xy 109.22 31.75)
		)
		(stroke
			(width 0)
			(type default)
		)
	)
	(wire
		(pts
			(xy 328.93 125.73) (xy 330.2 125.73)
		)
		(stroke
			(width 0)
			(type default)
		)
	)
	(wire
		(pts
			(xy 166.37 41.91) (xy 167.64 41.91)
		)
		(stroke
			(width 0)
			(type default)
		)
	)
	(bus
		(pts
			(xy 130.81 48.26) (xy 130.81 50.8)
		)
		(stroke
			(width 0)
			(type default)
		)
	)
	(wire
		(pts
			(xy 245.11 118.11) (xy 236.22 118.11)
		)
		(stroke
			(width 0)
			(type default)
		)
	)
	(wire
		(pts
			(xy 330.2 54.61) (xy 328.93 54.61)
		)
		(stroke
			(width 0)
			(type default)
		)
	)
	(bus
		(pts
			(xy 228.6 90.17) (xy 231.14 90.17)
		)
		(stroke
			(width 0)
			(type default)
		)
	)
	(wire
		(pts
			(xy 144.78 194.31) (xy 143.51 194.31)
		)
		(stroke
			(width 0)
			(type default)
		)
	)
	(wire
		(pts
			(xy 58.42 181.61) (xy 57.15 181.61)
		)
		(stroke
			(width 0)
			(type default)
		)
	)
	(wire
		(pts
			(xy 237.49 222.25) (xy 237.49 224.79)
		)
		(stroke
			(width 0)
			(type default)
		)
	)
	(wire
		(pts
			(xy 367.03 229.87) (xy 367.03 223.52)
		)
		(stroke
			(width 0)
			(type default)
		)
	)
	(wire
		(pts
			(xy 81.28 158.75) (xy 82.55 158.75)
		)
		(stroke
			(width 0)
			(type default)
		)
	)
	(wire
		(pts
			(xy 166.37 34.29) (xy 166.37 41.91)
		)
		(stroke
			(width 0)
			(type default)
		)
	)
	(wire
		(pts
			(xy 382.27 226.06) (xy 379.73 226.06)
		)
		(stroke
			(width 0)
			(type default)
		)
	)
	(wire
		(pts
			(xy 353.06 46.99) (xy 354.33 46.99)
		)
		(stroke
			(width 0)
			(type default)
		)
	)
	(wire
		(pts
			(xy 273.05 110.49) (xy 273.05 118.11)
		)
		(stroke
			(width 0)
			(type default)
		)
	)
	(wire
		(pts
			(xy 337.82 223.52) (xy 367.03 223.52)
		)
		(stroke
			(width 0)
			(type default)
		)
	)
	(wire
		(pts
			(xy 212.09 250.19) (xy 212.09 254)
		)
		(stroke
			(width 0)
			(type default)
		)
	)
	(wire
		(pts
			(xy 204.47 153.67) (xy 204.47 162.56)
		)
		(stroke
			(width 0)
			(type default)
		)
	)
	(wire
		(pts
			(xy 271.78 64.77) (xy 293.37 64.77)
		)
		(stroke
			(width 0)
			(type default)
		)
	)
	(wire
		(pts
			(xy 288.29 237.49) (xy 269.24 237.49)
		)
		(stroke
			(width 0)
			(type default)
		)
	)
	(wire
		(pts
			(xy 247.65 97.79) (xy 247.65 120.65)
		)
		(stroke
			(width 0)
			(type default)
		)
	)
	(wire
		(pts
			(xy 144.78 171.45) (xy 144.78 179.07)
		)
		(stroke
			(width 0)
			(type default)
		)
	)
	(wire
		(pts
			(xy 264.16 247.65) (xy 236.22 247.65)
		)
		(stroke
			(width 0)
			(type default)
		)
	)
	(bus
		(pts
			(xy 130.81 58.42) (xy 130.81 63.5)
		)
		(stroke
			(width 0)
			(type default)
		)
	)
	(wire
		(pts
			(xy 127 95.25) (xy 109.22 95.25)
		)
		(stroke
			(width 0)
			(type default)
		)
	)
	(wire
		(pts
			(xy 275.59 120.65) (xy 271.78 120.65)
		)
		(stroke
			(width 0)
			(type default)
		)
	)
	(bus
		(pts
			(xy 231.14 59.69) (xy 232.41 60.96)
		)
		(stroke
			(width 0)
			(type default)
		)
	)
	(wire
		(pts
			(xy 337.82 241.3) (xy 339.09 241.3)
		)
		(stroke
			(width 0)
			(type default)
		)
	)
	(wire
		(pts
			(xy 273.05 67.31) (xy 273.05 69.85)
		)
		(stroke
			(width 0)
			(type default)
		)
	)
	(wire
		(pts
			(xy 191.77 77.47) (xy 190.5 77.47)
		)
		(stroke
			(width 0)
			(type default)
		)
	)
	(wire
		(pts
			(xy 166.37 64.77) (xy 166.37 72.39)
		)
		(stroke
			(width 0)
			(type default)
		)
	)
	(bus
		(pts
			(xy 64.77 81.28) (xy 64.77 83.82)
		)
		(stroke
			(width 0)
			(type default)
		)
	)
	(wire
		(pts
			(xy 368.3 64.77) (xy 353.06 64.77)
		)
		(stroke
			(width 0)
			(type default)
		)
	)
	(wire
		(pts
			(xy 238.76 237.49) (xy 236.22 237.49)
		)
		(stroke
			(width 0)
			(type default)
		)
	)
	(wire
		(pts
			(xy 275.59 115.57) (xy 271.78 115.57)
		)
		(stroke
			(width 0)
			(type default)
		)
	)
	(wire
		(pts
			(xy 353.06 80.01) (xy 354.33 80.01)
		)
		(stroke
			(width 0)
			(type default)
		)
	)
	(wire
		(pts
			(xy 120.65 252.73) (xy 118.11 252.73)
		)
		(stroke
			(width 0)
			(type default)
		)
	)
	(wire
		(pts
			(xy 129.54 67.31) (xy 109.22 67.31)
		)
		(stroke
			(width 0)
			(type default)
		)
	)
	(bus
		(pts
			(xy 313.69 76.2) (xy 313.69 78.74)
		)
		(stroke
			(width 0)
			(type default)
		)
	)
	(wire
		(pts
			(xy 330.2 115.57) (xy 328.93 115.57)
		)
		(stroke
			(width 0)
			(type default)
		)
	)
	(wire
		(pts
			(xy 288.29 247.65) (xy 273.05 247.65)
		)
		(stroke
			(width 0)
			(type default)
		)
	)
	(wire
		(pts
			(xy 328.93 64.77) (xy 328.93 72.39)
		)
		(stroke
			(width 0)
			(type default)
		)
	)
	(wire
		(pts
			(xy 337.82 236.22) (xy 339.09 236.22)
		)
		(stroke
			(width 0)
			(type default)
		)
	)
	(wire
		(pts
			(xy 248.92 44.45) (xy 247.65 44.45)
		)
		(stroke
			(width 0)
			(type default)
		)
	)
	(wire
		(pts
			(xy 330.2 72.39) (xy 328.93 72.39)
		)
		(stroke
			(width 0)
			(type default)
		)
	)
	(wire
		(pts
			(xy 379.73 195.58) (xy 379.73 196.85)
		)
		(stroke
			(width 0)
			(type default)
		)
	)
	(wire
		(pts
			(xy 119.38 189.23) (xy 120.65 189.23)
		)
		(stroke
			(width 0)
			(type default)
		)
	)
	(wire
		(pts
			(xy 245.11 123.19) (xy 245.11 118.11)
		)
		(stroke
			(width 0)
			(type default)
		)
	)
	(bus
		(pts
			(xy 193.04 179.07) (xy 195.58 179.07)
		)
		(stroke
			(width 0)
			(type default)
		)
	)
	(wire
		(pts
			(xy 71.12 67.31) (xy 86.36 67.31)
		)
		(stroke
			(width 0)
			(type default)
		)
	)
	(wire
		(pts
			(xy 353.06 118.11) (xy 354.33 118.11)
		)
		(stroke
			(width 0)
			(type default)
		)
	)
	(wire
		(pts
			(xy 57.15 194.31) (xy 57.15 201.93)
		)
		(stroke
			(width 0)
			(type default)
		)
	)
	(wire
		(pts
			(xy 271.78 39.37) (xy 273.05 39.37)
		)
		(stroke
			(width 0)
			(type default)
		)
	)
	(wire
		(pts
			(xy 233.68 95.25) (xy 248.92 95.25)
		)
		(stroke
			(width 0)
			(type default)
		)
	)
	(wire
		(pts
			(xy 66.04 74.93) (xy 86.36 74.93)
		)
		(stroke
			(width 0)
			(type default)
		)
	)
	(wire
		(pts
			(xy 379.73 236.22) (xy 379.73 234.95)
		)
		(stroke
			(width 0)
			(type default)
		)
	)
	(wire
		(pts
			(xy 256.54 240.03) (xy 241.3 240.03)
		)
		(stroke
			(width 0)
			(type default)
		)
	)
	(wire
		(pts
			(xy 251.46 199.39) (xy 236.22 199.39)
		)
		(stroke
			(width 0)
			(type default)
		)
	)
	(wire
		(pts
			(xy 86.36 57.15) (xy 85.09 57.15)
		)
		(stroke
			(width 0)
			(type default)
		)
	)
	(wire
		(pts
			(xy 81.28 156.21) (xy 82.55 156.21)
		)
		(stroke
			(width 0)
			(type default)
		)
	)
	(wire
		(pts
			(xy 330.2 31.75) (xy 328.93 31.75)
		)
		(stroke
			(width 0)
			(type default)
		)
	)
	(wire
		(pts
			(xy 110.49 36.83) (xy 110.49 39.37)
		)
		(stroke
			(width 0)
			(type default)
		)
	)
	(wire
		(pts
			(xy 387.35 215.9) (xy 397.51 215.9)
		)
		(stroke
			(width 0)
			(type default)
		)
	)
	(bus
		(pts
			(xy 68.58 57.15) (xy 69.85 58.42)
		)
		(stroke
			(width 0)
			(type default)
		)
	)
	(wire
		(pts
			(xy 354.33 39.37) (xy 354.33 46.99)
		)
		(stroke
			(width 0)
			(type default)
		)
	)
	(wire
		(pts
			(xy 210.82 242.57) (xy 213.36 242.57)
		)
		(stroke
			(width 0)
			(type default)
		)
	)
	(wire
		(pts
			(xy 247.65 67.31) (xy 247.65 74.93)
		)
		(stroke
			(width 0)
			(type default)
		)
	)
	(wire
		(pts
			(xy 57.15 212.09) (xy 57.15 214.63)
		)
		(stroke
			(width 0)
			(type default)
		)
	)
	(bus
		(pts
			(xy 64.77 72.39) (xy 64.77 73.66)
		)
		(stroke
			(width 0)
			(type default)
		)
	)
	(wire
		(pts
			(xy 86.36 31.75) (xy 85.09 31.75)
		)
		(stroke
			(width 0)
			(type default)
		)
	)
	(wire
		(pts
			(xy 353.06 49.53) (xy 354.33 49.53)
		)
		(stroke
			(width 0)
			(type default)
		)
	)
	(wire
		(pts
			(xy 237.49 204.47) (xy 237.49 212.09)
		)
		(stroke
			(width 0)
			(type default)
		)
	)
	(wire
		(pts
			(xy 97.79 250.19) (xy 97.79 248.92)
		)
		(stroke
			(width 0)
			(type default)
		)
	)
	(wire
		(pts
			(xy 271.78 113.03) (xy 285.75 113.03)
		)
		(stroke
			(width 0)
			(type default)
		)
	)
	(wire
		(pts
			(xy 57.15 234.95) (xy 57.15 242.57)
		)
		(stroke
			(width 0)
			(type default)
		)
	)
	(wire
		(pts
			(xy 129.54 59.69) (xy 109.22 59.69)
		)
		(stroke
			(width 0)
			(type default)
		)
	)
	(wire
		(pts
			(xy 173.99 232.41) (xy 208.28 232.41)
		)
		(stroke
			(width 0)
			(type default)
		)
	)
	(wire
		(pts
			(xy 82.55 156.21) (xy 82.55 158.75)
		)
		(stroke
			(width 0)
			(type default)
		)
	)
	(wire
		(pts
			(xy 212.09 247.65) (xy 212.09 250.19)
		)
		(stroke
			(width 0)
			(type default)
		)
	)
	(wire
		(pts
			(xy 72.39 24.13) (xy 72.39 25.4)
		)
		(stroke
			(width 0)
			(type default)
		)
	)
	(wire
		(pts
			(xy 81.28 219.71) (xy 82.55 219.71)
		)
		(stroke
			(width 0)
			(type default)
		)
	)
	(wire
		(pts
			(xy 81.28 209.55) (xy 82.55 209.55)
		)
		(stroke
			(width 0)
			(type default)
		)
	)
	(wire
		(pts
			(xy 236.22 173.99) (xy 237.49 173.99)
		)
		(stroke
			(width 0)
			(type default)
		)
	)
	(wire
		(pts
			(xy 368.3 34.29) (xy 353.06 34.29)
		)
		(stroke
			(width 0)
			(type default)
		)
	)
	(wire
		(pts
			(xy 166.37 49.53) (xy 166.37 57.15)
		)
		(stroke
			(width 0)
			(type default)
		)
	)
	(wire
		(pts
			(xy 354.33 77.47) (xy 354.33 80.01)
		)
		(stroke
			(width 0)
			(type default)
		)
	)
	(wire
		(pts
			(xy 191.77 92.71) (xy 190.5 92.71)
		)
		(stroke
			(width 0)
			(type default)
		)
	)
	(wire
		(pts
			(xy 237.49 254) (xy 237.49 252.73)
		)
		(stroke
			(width 0)
			(type default)
		)
	)
	(wire
		(pts
			(xy 143.51 209.55) (xy 144.78 209.55)
		)
		(stroke
			(width 0)
			(type default)
		)
	)
	(wire
		(pts
			(xy 353.06 29.21) (xy 354.33 29.21)
		)
		(stroke
			(width 0)
			(type default)
		)
	)
	(bus
		(pts
			(xy 369.57 50.8) (xy 369.57 53.34)
		)
		(stroke
			(width 0)
			(type default)
		)
	)
	(wire
		(pts
			(xy 212.09 250.19) (xy 213.36 250.19)
		)
		(stroke
			(width 0)
			(type default)
		)
	)
	(wire
		(pts
			(xy 273.05 46.99) (xy 273.05 49.53)
		)
		(stroke
			(width 0)
			(type default)
		)
	)
	(wire
		(pts
			(xy 86.36 29.21) (xy 83.82 29.21)
		)
		(stroke
			(width 0)
			(type default)
		)
	)
	(wire
		(pts
			(xy 86.36 105.41) (xy 66.04 105.41)
		)
		(stroke
			(width 0)
			(type default)
		)
	)
	(wire
		(pts
			(xy 271.78 92.71) (xy 292.1 92.71)
		)
		(stroke
			(width 0)
			(type default)
		)
	)
	(wire
		(pts
			(xy 273.05 100.33) (xy 273.05 107.95)
		)
		(stroke
			(width 0)
			(type default)
		)
	)
	(wire
		(pts
			(xy 144.78 232.41) (xy 144.78 240.03)
		)
		(stroke
			(width 0)
			(type default)
		)
	)
	(bus
		(pts
			(xy 369.57 60.96) (xy 369.57 63.5)
		)
		(stroke
			(width 0)
			(type default)
		)
	)
	(wire
		(pts
			(xy 57.15 254) (xy 57.15 252.73)
		)
		(stroke
			(width 0)
			(type default)
		)
	)
	(wire
		(pts
			(xy 212.09 156.21) (xy 212.09 158.75)
		)
		(stroke
			(width 0)
			(type default)
		)
	)
	(bus
		(pts
			(xy 130.81 102.87) (xy 129.54 102.87)
		)
		(stroke
			(width 0)
			(type default)
		)
	)
	(bus
		(pts
			(xy 64.77 76.2) (xy 64.77 81.28)
		)
		(stroke
			(width 0)
			(type default)
		)
	)
	(bus
		(pts
			(xy 134.62 39.37) (xy 132.08 39.37)
		)
		(stroke
			(width 0)
			(type default)
		)
	)
	(wire
		(pts
			(xy 328.93 182.88) (xy 335.28 182.88)
		)
		(stroke
			(width 0)
			(type default)
		)
	)
	(wire
		(pts
			(xy 58.42 153.67) (xy 57.15 153.67)
		)
		(stroke
			(width 0)
			(type default)
		)
	)
	(wire
		(pts
			(xy 86.36 245.11) (xy 86.36 252.73)
		)
		(stroke
			(width 0)
			(type default)
		)
	)
	(wire
		(pts
			(xy 127 82.55) (xy 109.22 82.55)
		)
		(stroke
			(width 0)
			(type default)
		)
	)
	(wire
		(pts
			(xy 57.15 163.83) (xy 57.15 171.45)
		)
		(stroke
			(width 0)
			(type default)
		)
	)
	(wire
		(pts
			(xy 86.36 59.69) (xy 71.12 59.69)
		)
		(stroke
			(width 0)
			(type default)
		)
	)
	(wire
		(pts
			(xy 271.78 118.11) (xy 273.05 118.11)
		)
		(stroke
			(width 0)
			(type default)
		)
	)
	(wire
		(pts
			(xy 354.33 110.49) (xy 354.33 118.11)
		)
		(stroke
			(width 0)
			(type default)
		)
	)
	(wire
		(pts
			(xy 86.36 90.17) (xy 66.04 90.17)
		)
		(stroke
			(width 0)
			(type default)
		)
	)
	(wire
		(pts
			(xy 247.65 31.75) (xy 248.92 31.75)
		)
		(stroke
			(width 0)
			(type default)
		)
	)
	(wire
		(pts
			(xy 58.42 234.95) (xy 57.15 234.95)
		)
		(stroke
			(width 0)
			(type default)
		)
	)
	(wire
		(pts
			(xy 57.15 214.63) (xy 57.15 222.25)
		)
		(stroke
			(width 0)
			(type default)
		)
	)
	(wire
		(pts
			(xy 271.78 36.83) (xy 273.05 36.83)
		)
		(stroke
			(width 0)
			(type default)
		)
	)
	(wire
		(pts
			(xy 212.09 166.37) (xy 212.09 168.91)
		)
		(stroke
			(width 0)
			(type default)
		)
	)
	(wire
		(pts
			(xy 191.77 62.23) (xy 190.5 62.23)
		)
		(stroke
			(width 0)
			(type default)
		)
	)
	(wire
		(pts
			(xy 354.33 128.27) (xy 353.06 128.27)
		)
		(stroke
			(width 0)
			(type default)
		)
	)
	(wire
		(pts
			(xy 353.06 90.17) (xy 354.33 90.17)
		)
		(stroke
			(width 0)
			(type default)
		)
	)
	(wire
		(pts
			(xy 144.78 161.29) (xy 144.78 163.83)
		)
		(stroke
			(width 0)
			(type default)
		)
	)
	(wire
		(pts
			(xy 181.61 157.48) (xy 181.61 158.75)
		)
		(stroke
			(width 0)
			(type default)
		)
	)
	(bus
		(pts
			(xy 369.57 30.48) (xy 370.84 29.21)
		)
		(stroke
			(width 0)
			(type default)
		)
	)
	(wire
		(pts
			(xy 354.33 87.63) (xy 354.33 90.17)
		)
		(stroke
			(width 0)
			(type default)
		)
	)
	(wire
		(pts
			(xy 354.33 90.17) (xy 354.33 97.79)
		)
		(stroke
			(width 0)
			(type default)
		)
	)
	(wire
		(pts
			(xy 58.42 214.63) (xy 57.15 214.63)
		)
		(stroke
			(width 0)
			(type default)
		)
	)
	(wire
		(pts
			(xy 82.55 196.85) (xy 82.55 199.39)
		)
		(stroke
			(width 0)
			(type default)
		)
	)
	(bus
		(pts
			(xy 294.64 50.8) (xy 294.64 53.34)
		)
		(stroke
			(width 0)
			(type default)
		)
	)
	(wire
		(pts
			(xy 358.14 176.53) (xy 358.14 180.34)
		)
		(stroke
			(width 0)
			(type default)
		)
	)
	(wire
		(pts
			(xy 167.64 29.21) (xy 165.1 29.21)
		)
		(stroke
			(width 0)
			(type default)
		)
	)
	(wire
		(pts
			(xy 358.14 226.06) (xy 358.14 229.87)
		)
		(stroke
			(width 0)
			(type default)
		)
	)
	(wire
		(pts
			(xy 213.36 179.07) (xy 212.09 179.07)
		)
		(stroke
			(width 0)
			(type default)
		)
	)
	(bus
		(pts
			(xy 129.54 69.85) (xy 128.27 71.12)
		)
		(stroke
			(width 0)
			(type default)
		)
	)
	(wire
		(pts
			(xy 237.49 191.77) (xy 237.49 194.31)
		)
		(stroke
			(width 0)
			(type default)
		)
	)
	(wire
		(pts
			(xy 353.06 181.61) (xy 353.06 187.96)
		)
		(stroke
			(width 0)
			(type default)
		)
	)
	(wire
		(pts
			(xy 273.05 90.17) (xy 273.05 97.79)
		)
		(stroke
			(width 0)
			(type default)
		)
	)
	(bus
		(pts
			(xy 128.27 88.9) (xy 128.27 93.98)
		)
		(stroke
			(width 0)
			(type default)
		)
	)
	(wire
		(pts
			(xy 110.49 115.57) (xy 109.22 115.57)
		)
		(stroke
			(width 0)
			(type default)
		)
	)
	(wire
		(pts
			(xy 119.38 219.71) (xy 119.38 227.33)
		)
		(stroke
			(width 0)
			(type default)
		)
	)
	(wire
		(pts
			(xy 368.3 74.93) (xy 353.06 74.93)
		)
		(stroke
			(width 0)
			(type default)
		)
	)
	(wire
		(pts
			(xy 144.78 217.17) (xy 144.78 224.79)
		)
		(stroke
			(width 0)
			(type default)
		)
	)
	(wire
		(pts
			(xy 71.12 69.85) (xy 86.36 69.85)
		)
		(stroke
			(width 0)
			(type default)
		)
	)
	(wire
		(pts
			(xy 273.05 128.27) (xy 273.05 129.54)
		)
		(stroke
			(width 0)
			(type default)
		)
	)
	(wire
		(pts
			(xy 208.28 242.57) (xy 210.82 245.11)
		)
		(stroke
			(width 0)
			(type default)
		)
	)
	(wire
		(pts
			(xy 144.78 194.31) (xy 144.78 201.93)
		)
		(stroke
			(width 0)
			(type default)
		)
	)
	(wire
		(pts
			(xy 212.09 229.87) (xy 212.09 237.49)
		)
		(stroke
			(width 0)
			(type default)
		)
	)
	(wire
		(pts
			(xy 328.93 95.25) (xy 328.93 102.87)
		)
		(stroke
			(width 0)
			(type default)
		)
	)
	(wire
		(pts
			(xy 81.28 227.33) (xy 82.55 227.33)
		)
		(stroke
			(width 0)
			(type default)
		)
	)
	(bus
		(pts
			(xy 292.1 72.39) (xy 289.56 72.39)
		)
		(stroke
			(width 0)
			(type default)
		)
	)
	(bus
		(pts
			(xy 64.77 96.52) (xy 64.77 99.06)
		)
		(stroke
			(width 0)
			(type default)
		)
	)
	(wire
		(pts
			(xy 71.12 46.99) (xy 86.36 46.99)
		)
		(stroke
			(width 0)
			(type default)
		)
	)
	(wire
		(pts
			(xy 166.37 41.91) (xy 166.37 49.53)
		)
		(stroke
			(width 0)
			(type default)
		)
	)
	(wire
		(pts
			(xy 82.55 217.17) (xy 82.55 219.71)
		)
		(stroke
			(width 0)
			(type default)
		)
	)
	(wire
		(pts
			(xy 337.82 231.14) (xy 339.09 231.14)
		)
		(stroke
			(width 0)
			(type default)
		)
	)
	(wire
		(pts
			(xy 144.78 179.07) (xy 144.78 186.69)
		)
		(stroke
			(width 0)
			(type default)
		)
	)
	(bus
		(pts
			(xy 68.58 64.77) (xy 69.85 66.04)
		)
		(stroke
			(width 0)
			(type default)
		)
	)
	(wire
		(pts
			(xy 354.33 97.79) (xy 354.33 100.33)
		)
		(stroke
			(width 0)
			(type default)
		)
	)
	(bus
		(pts
			(xy 323.85 173.99) (xy 325.12 175.26)
		)
		(stroke
			(width 0)
			(type default)
		)
	)
	(wire
		(pts
			(xy 288.29 217.17) (xy 241.3 217.17)
		)
		(stroke
			(width 0)
			(type default)
		)
	)
	(wire
		(pts
			(xy 339.09 242.57) (xy 339.09 241.3)
		)
		(stroke
			(width 0)
			(type default)
		)
	)
	(wire
		(pts
			(xy 144.78 247.65) (xy 143.51 247.65)
		)
		(stroke
			(width 0)
			(type default)
		)
	)
	(wire
		(pts
			(xy 328.93 31.75) (xy 328.93 34.29)
		)
		(stroke
			(width 0)
			(type default)
		)
	)
	(wire
		(pts
			(xy 213.36 209.55) (xy 212.09 209.55)
		)
		(stroke
			(width 0)
			(type default)
		)
	)
	(bus
		(pts
			(xy 232.41 83.82) (xy 232.41 86.36)
		)
		(stroke
			(width 0)
			(type default)
		)
	)
	(wire
		(pts
			(xy 212.09 227.33) (xy 212.09 229.87)
		)
		(stroke
			(width 0)
			(type default)
		)
	)
	(wire
		(pts
			(xy 238.76 217.17) (xy 236.22 217.17)
		)
		(stroke
			(width 0)
			(type default)
		)
	)
	(bus
		(pts
			(xy 69.85 58.42) (xy 69.85 60.96)
		)
		(stroke
			(width 0)
			(type default)
		)
	)
	(wire
		(pts
			(xy 287.02 74.93) (xy 271.78 74.93)
		)
		(stroke
			(width 0)
			(type default)
		)
	)
	(bus
		(pts
			(xy 132.08 54.61) (xy 130.81 55.88)
		)
		(stroke
			(width 0)
			(type default)
		)
	)
	(wire
		(pts
			(xy 248.92 62.23) (xy 233.68 62.23)
		)
		(stroke
			(width 0)
			(type default)
		)
	)
	(wire
		(pts
			(xy 110.49 39.37) (xy 109.22 39.37)
		)
		(stroke
			(width 0)
			(type default)
		)
	)
	(wire
		(pts
			(xy 86.36 125.73) (xy 85.09 125.73)
		)
		(stroke
			(width 0)
			(type default)
		)
	)
	(bus
		(pts
			(xy 69.85 50.8) (xy 69.85 53.34)
		)
		(stroke
			(width 0)
			(type default)
		)
	)
	(wire
		(pts
			(xy 119.38 234.95) (xy 120.65 234.95)
		)
		(stroke
			(width 0)
			(type default)
		)
	)
	(wire
		(pts
			(xy 129.54 49.53) (xy 109.22 49.53)
		)
		(stroke
			(width 0)
			(type default)
		)
	)
	(bus
		(pts
			(xy 196.85 180.34) (xy 195.58 179.07)
		)
		(stroke
			(width 0)
			(type default)
		)
	)
	(wire
		(pts
			(xy 144.78 240.03) (xy 143.51 240.03)
		)
		(stroke
			(width 0)
			(type default)
		)
	)
	(wire
		(pts
			(xy 85.09 110.49) (xy 85.09 118.11)
		)
		(stroke
			(width 0)
			(type default)
		)
	)
	(wire
		(pts
			(xy 248.92 29.21) (xy 246.38 29.21)
		)
		(stroke
			(width 0)
			(type default)
		)
	)
	(wire
		(pts
			(xy 354.33 29.21) (xy 354.33 36.83)
		)
		(stroke
			(width 0)
			(type default)
		)
	)
	(wire
		(pts
			(xy 328.93 123.19) (xy 330.2 123.19)
		)
		(stroke
			(width 0)
			(type default)
		)
	)
	(wire
		(pts
			(xy 236.22 163.83) (xy 237.49 163.83)
		)
		(stroke
			(width 0)
			(type default)
		)
	)
	(bus
		(pts
			(xy 313.69 35.56) (xy 312.42 34.29)
		)
		(stroke
			(width 0)
			(type default)
		)
	)
	(bus
		(pts
			(xy 128.27 73.66) (xy 128.27 78.74)
		)
		(stroke
			(width 0)
			(type default)
		)
	)
	(wire
		(pts
			(xy 57.15 232.41) (xy 57.15 234.95)
		)
		(stroke
			(width 0)
			(type default)
		)
	)
	(wire
		(pts
			(xy 81.28 186.69) (xy 82.55 186.69)
		)
		(stroke
			(width 0)
			(type default)
		)
	)
	(bus
		(pts
			(xy 289.56 218.44) (xy 289.56 226.06)
		)
		(stroke
			(width 0)
			(type default)
		)
	)
	(wire
		(pts
			(xy 212.09 217.17) (xy 212.09 219.71)
		)
		(stroke
			(width 0)
			(type default)
		)
	)
	(bus
		(pts
			(xy 231.14 44.45) (xy 232.41 45.72)
		)
		(stroke
			(width 0)
			(type default)
		)
	)
	(bus
		(pts
			(xy 68.58 41.91) (xy 69.85 43.18)
		)
		(stroke
			(width 0)
			(type default)
		)
	)
	(bus
		(pts
			(xy 292.1 69.85) (xy 289.56 69.85)
		)
		(stroke
			(width 0)
			(type default)
		)
	)
	(wire
		(pts
			(xy 86.36 128.27) (xy 71.12 128.27)
		)
		(stroke
			(width 0)
			(type default)
		)
	)
	(wire
		(pts
			(xy 210.82 234.95) (xy 213.36 234.95)
		)
		(stroke
			(width 0)
			(type default)
		)
	)
	(bus
		(pts
			(xy 64.77 104.14) (xy 64.77 106.68)
		)
		(stroke
			(width 0)
			(type default)
		)
	)
	(wire
		(pts
			(xy 166.37 31.75) (xy 166.37 34.29)
		)
		(stroke
			(width 0)
			(type default)
		)
	)
	(wire
		(pts
			(xy 144.78 252.73) (xy 144.78 254)
		)
		(stroke
			(width 0)
			(type default)
		)
	)
	(bus
		(pts
			(xy 128.27 93.98) (xy 128.27 96.52)
		)
		(stroke
			(width 0)
			(type default)
		)
	)
	(bus
		(pts
			(xy 172.72 220.98) (xy 172.72 223.52)
		)
		(stroke
			(width 0)
			(type default)
		)
	)
	(wire
		(pts
			(xy 236.22 232.41) (xy 237.49 232.41)
		)
		(stroke
			(width 0)
			(type default)
		)
	)
	(wire
		(pts
			(xy 248.92 82.55) (xy 247.65 82.55)
		)
		(stroke
			(width 0)
			(type default)
		)
	)
	(wire
		(pts
			(xy 129.54 34.29) (xy 109.22 34.29)
		)
		(stroke
			(width 0)
			(type default)
		)
	)
	(wire
		(pts
			(xy 354.33 67.31) (xy 354.33 69.85)
		)
		(stroke
			(width 0)
			(type default)
		)
	)
	(wire
		(pts
			(xy 82.55 237.49) (xy 82.55 240.03)
		)
		(stroke
			(width 0)
			(type default)
		)
	)
	(wire
		(pts
			(xy 173.99 234.95) (xy 208.28 234.95)
		)
		(stroke
			(width 0)
			(type default)
		)
	)
	(wire
		(pts
			(xy 353.06 120.65) (xy 354.33 120.65)
		)
		(stroke
			(width 0)
			(type default)
		)
	)
	(wire
		(pts
			(xy 119.38 181.61) (xy 119.38 189.23)
		)
		(stroke
			(width 0)
			(type default)
		)
	)
	(wire
		(pts
			(xy 335.28 187.96) (xy 334.01 187.96)
		)
		(stroke
			(width 0)
			(type default)
		)
	)
	(wire
		(pts
			(xy 247.65 120.65) (xy 247.65 125.73)
		)
		(stroke
			(width 0)
			(type default)
		)
	)
	(wire
		(pts
			(xy 326.39 176.53) (xy 335.28 176.53)
		)
		(stroke
			(width 0)
			(type default)
		)
	)
	(wire
		(pts
			(xy 328.93 41.91) (xy 328.93 44.45)
		)
		(stroke
			(width 0)
			(type default)
		)
	)
	(bus
		(pts
			(xy 373.38 29.21) (xy 370.84 29.21)
		)
		(stroke
			(width 0)
			(type default)
		)
	)
	(wire
		(pts
			(xy 58.42 232.41) (xy 57.15 232.41)
		)
		(stroke
			(width 0)
			(type default)
		)
	)
	(wire
		(pts
			(xy 330.2 52.07) (xy 328.93 52.07)
		)
		(stroke
			(width 0)
			(type default)
		)
	)
	(wire
		(pts
			(xy 194.31 242.57) (xy 208.28 242.57)
		)
		(stroke
			(width 0)
			(type default)
		)
	)
	(wire
		(pts
			(xy 57.15 245.11) (xy 57.15 252.73)
		)
		(stroke
			(width 0)
			(type default)
		)
	)
	(wire
		(pts
			(xy 271.78 107.95) (xy 273.05 107.95)
		)
		(stroke
			(width 0)
			(type default)
		)
	)
	(wire
		(pts
			(xy 173.99 224.79) (xy 193.04 224.79)
		)
		(stroke
			(width 0)
			(type default)
		)
	)
	(wire
		(pts
			(xy 233.68 85.09) (xy 248.92 85.09)
		)
		(stroke
			(width 0)
			(type default)
		)
	)
	(wire
		(pts
			(xy 110.49 29.21) (xy 110.49 36.83)
		)
		(stroke
			(width 0)
			(type default)
		)
	)
	(bus
		(pts
			(xy 252.73 175.26) (xy 254 173.99)
		)
		(stroke
			(width 0)
			(type default)
		)
	)
	(wire
		(pts
			(xy 353.06 57.15) (xy 354.33 57.15)
		)
		(stroke
			(width 0)
			(type default)
		)
	)
	(wire
		(pts
			(xy 328.93 74.93) (xy 328.93 82.55)
		)
		(stroke
			(width 0)
			(type default)
		)
	)
	(bus
		(pts
			(xy 252.73 175.26) (xy 252.73 177.8)
		)
		(stroke
			(width 0)
			(type default)
		)
	)
	(wire
		(pts
			(xy 241.3 240.03) (xy 238.76 237.49)
		)
		(stroke
			(width 0)
			(type default)
		)
	)
	(wire
		(pts
			(xy 85.09 80.01) (xy 85.09 87.63)
		)
		(stroke
			(width 0)
			(type default)
		)
	)
	(wire
		(pts
			(xy 248.92 59.69) (xy 247.65 59.69)
		)
		(stroke
			(width 0)
			(type default)
		)
	)
	(bus
		(pts
			(xy 130.81 69.85) (xy 129.54 69.85)
		)
		(stroke
			(width 0)
			(type default)
		)
	)
	(wire
		(pts
			(xy 144.78 163.83) (xy 144.78 171.45)
		)
		(stroke
			(width 0)
			(type default)
		)
	)
	(bus
		(pts
			(xy 132.08 39.37) (xy 130.81 40.64)
		)
		(stroke
			(width 0)
			(type default)
		)
	)
	(wire
		(pts
			(xy 236.22 153.67) (xy 237.49 153.67)
		)
		(stroke
			(width 0)
			(type default)
		)
	)
	(wire
		(pts
			(xy 273.05 118.11) (xy 273.05 123.19)
		)
		(stroke
			(width 0)
			(type default)
		)
	)
	(wire
		(pts
			(xy 119.38 212.09) (xy 119.38 219.71)
		)
		(stroke
			(width 0)
			(type default)
		)
	)
	(bus
		(pts
			(xy 256.54 173.99) (xy 254 173.99)
		)
		(stroke
			(width 0)
			(type default)
		)
	)
	(wire
		(pts
			(xy 368.3 41.91) (xy 353.06 41.91)
		)
		(stroke
			(width 0)
			(type default)
		)
	)
	(wire
		(pts
			(xy 236.22 222.25) (xy 237.49 222.25)
		)
		(stroke
			(width 0)
			(type default)
		)
	)
	(wire
		(pts
			(xy 85.09 102.87) (xy 86.36 102.87)
		)
		(stroke
			(width 0)
			(type default)
		)
	)
	(wire
		(pts
			(xy 212.09 189.23) (xy 212.09 196.85)
		)
		(stroke
			(width 0)
			(type default)
		)
	)
	(wire
		(pts
			(xy 82.55 189.23) (xy 82.55 196.85)
		)
		(stroke
			(width 0)
			(type default)
		)
	)
	(bus
		(pts
			(xy 292.1 80.01) (xy 289.56 80.01)
		)
		(stroke
			(width 0)
			(type default)
		)
	)
	(wire
		(pts
			(xy 273.05 87.63) (xy 273.05 90.17)
		)
		(stroke
			(width 0)
			(type default)
		)
	)
	(wire
		(pts
			(xy 213.36 156.21) (xy 212.09 156.21)
		)
		(stroke
			(width 0)
			(type default)
		)
	)
	(wire
		(pts
			(xy 119.38 196.85) (xy 119.38 204.47)
		)
		(stroke
			(width 0)
			(type default)
		)
	)
	(wire
		(pts
			(xy 213.36 237.49) (xy 212.09 237.49)
		)
		(stroke
			(width 0)
			(type default)
		)
	)
	(bus
		(pts
			(xy 228.6 44.45) (xy 231.14 44.45)
		)
		(stroke
			(width 0)
			(type default)
		)
	)
	(wire
		(pts
			(xy 71.12 44.45) (xy 86.36 44.45)
		)
		(stroke
			(width 0)
			(type default)
		)
	)
	(wire
		(pts
			(xy 367.03 236.22) (xy 367.03 234.95)
		)
		(stroke
			(width 0)
			(type default)
		)
	)
	(wire
		(pts
			(xy 191.77 123.19) (xy 191.77 128.27)
		)
		(stroke
			(width 0)
			(type default)
		)
	)
	(wire
		(pts
			(xy 144.78 224.79) (xy 143.51 224.79)
		)
		(stroke
			(width 0)
			(type default)
		)
	)
	(wire
		(pts
			(xy 144.78 224.79) (xy 144.78 232.41)
		)
		(stroke
			(width 0)
			(type default)
		)
	)
	(wire
		(pts
			(xy 58.42 161.29) (xy 57.15 161.29)
		)
		(stroke
			(width 0)
			(type default)
		)
	)
	(wire
		(pts
			(xy 212.09 199.39) (xy 212.09 207.01)
		)
		(stroke
			(width 0)
			(type default)
		)
	)
	(wire
		(pts
			(xy 185.42 157.48) (xy 181.61 157.48)
		)
		(stroke
			(width 0)
			(type default)
		)
	)
	(wire
		(pts
			(xy 273.05 128.27) (xy 271.78 128.27)
		)
		(stroke
			(width 0)
			(type default)
		)
	)
	(bus
		(pts
			(xy 294.64 82.55) (xy 293.37 83.82)
		)
		(stroke
			(width 0)
			(type default)
		)
	)
	(bus
		(pts
			(xy 128.27 81.28) (xy 128.27 86.36)
		)
		(stroke
			(width 0)
			(type default)
		)
	)
	(wire
		(pts
			(xy 166.37 87.63) (xy 167.64 87.63)
		)
		(stroke
			(width 0)
			(type default)
		)
	)
	(wire
		(pts
			(xy 191.77 69.85) (xy 191.77 77.47)
		)
		(stroke
			(width 0)
			(type default)
		)
	)
	(bus
		(pts
			(xy 66.04 41.91) (xy 68.58 41.91)
		)
		(stroke
			(width 0)
			(type default)
		)
	)
	(wire
		(pts
			(xy 191.77 46.99) (xy 191.77 54.61)
		)
		(stroke
			(width 0)
			(type default)
		)
	)
	(wire
		(pts
			(xy 382.27 205.74) (xy 379.73 205.74)
		)
		(stroke
			(width 0)
			(type default)
		)
	)
	(wire
		(pts
			(xy 82.55 209.55) (xy 82.55 217.17)
		)
		(stroke
			(width 0)
			(type default)
		)
	)
	(wire
		(pts
			(xy 271.78 67.31) (xy 273.05 67.31)
		)
		(stroke
			(width 0)
			(type default)
		)
	)
	(wire
		(pts
			(xy 389.89 180.34) (xy 393.7 180.34)
		)
		(stroke
			(width 0)
			(type default)
		)
	)
	(wire
		(pts
			(xy 389.89 185.42) (xy 393.7 185.42)
		)
		(stroke
			(width 0)
			(type default)
		)
	)
	(wire
		(pts
			(xy 251.46 189.23) (xy 236.22 189.23)
		)
		(stroke
			(width 0)
			(type default)
		)
	)
	(wire
		(pts
			(xy 270.51 250.19) (xy 273.05 247.65)
		)
		(stroke
			(width 0)
			(type default)
		)
	)
	(bus
		(pts
			(xy 132.08 29.21) (xy 130.81 30.48)
		)
		(stroke
			(width 0)
			(type default)
		)
	)
	(bus
		(pts
			(xy 297.18 82.55) (xy 294.64 82.55)
		)
		(stroke
			(width 0)
			(type default)
		)
	)
	(wire
		(pts
			(xy 284.48 105.41) (xy 271.78 105.41)
		)
		(stroke
			(width 0)
			(type default)
		)
	)
	(wire
		(pts
			(xy 284.48 102.87) (xy 271.78 102.87)
		)
		(stroke
			(width 0)
			(type default)
		)
	)
	(wire
		(pts
			(xy 119.38 173.99) (xy 119.38 181.61)
		)
		(stroke
			(width 0)
			(type default)
		)
	)
	(wire
		(pts
			(xy 82.55 250.19) (xy 82.55 254)
		)
		(stroke
			(width 0)
			(type default)
		)
	)
	(wire
		(pts
			(xy 144.78 171.45) (xy 143.51 171.45)
		)
		(stroke
			(width 0)
			(type default)
		)
	)
	(wire
		(pts
			(xy 328.93 54.61) (xy 328.93 62.23)
		)
		(stroke
			(width 0)
			(type default)
		)
	)
	(wire
		(pts
			(xy 213.36 189.23) (xy 212.09 189.23)
		)
		(stroke
			(width 0)
			(type default)
		)
	)
	(wire
		(pts
			(xy 236.22 214.63) (xy 237.49 214.63)
		)
		(stroke
			(width 0)
			(type default)
		)
	)
	(wire
		(pts
			(xy 387.35 236.22) (xy 397.51 236.22)
		)
		(stroke
			(width 0)
			(type default)
		)
	)
	(wire
		(pts
			(xy 198.12 224.79) (xy 213.36 224.79)
		)
		(stroke
			(width 0)
			(type default)
		)
	)
	(wire
		(pts
			(xy 190.5 157.48) (xy 191.77 157.48)
		)
		(stroke
			(width 0)
			(type default)
		)
	)
	(wire
		(pts
			(xy 66.04 82.55) (xy 86.36 82.55)
		)
		(stroke
			(width 0)
			(type default)
		)
	)
	(wire
		(pts
			(xy 143.51 250.19) (xy 146.05 250.19)
		)
		(stroke
			(width 0)
			(type default)
		)
	)
	(wire
		(pts
			(xy 237.49 201.93) (xy 237.49 204.47)
		)
		(stroke
			(width 0)
			(type default)
		)
	)
	(bus
		(pts
			(xy 63.5 95.25) (xy 64.77 96.52)
		)
		(stroke
			(width 0)
			(type default)
		)
	)
	(bus
		(pts
			(xy 171.45 219.71) (xy 172.72 220.98)
		)
		(stroke
			(width 0)
			(type default)
		)
	)
	(wire
		(pts
			(xy 82.55 240.03) (xy 82.55 247.65)
		)
		(stroke
			(width 0)
			(type default)
		)
	)
	(bus
		(pts
			(xy 64.77 99.06) (xy 64.77 104.14)
		)
		(stroke
			(width 0)
			(type default)
		)
	)
	(bus
		(pts
			(xy 325.12 175.26) (xy 325.12 177.8)
		)
		(stroke
			(width 0)
			(type default)
		)
	)
	(bus
		(pts
			(xy 313.69 58.42) (xy 313.69 66.04)
		)
		(stroke
			(width 0)
			(type default)
		)
	)
	(wire
		(pts
			(xy 82.55 179.07) (xy 82.55 186.69)
		)
		(stroke
			(width 0)
			(type default)
		)
	)
	(bus
		(pts
			(xy 313.69 68.58) (xy 313.69 76.2)
		)
		(stroke
			(width 0)
			(type default)
		)
	)
	(wire
		(pts
			(xy 213.36 158.75) (xy 212.09 158.75)
		)
		(stroke
			(width 0)
			(type default)
		)
	)
	(bus
		(pts
			(xy 69.85 43.18) (xy 69.85 45.72)
		)
		(stroke
			(width 0)
			(type default)
		)
	)
	(bus
		(pts
			(xy 130.81 30.48) (xy 130.81 33.02)
		)
		(stroke
			(width 0)
			(type default)
		)
	)
	(wire
		(pts
			(xy 119.38 242.57) (xy 119.38 250.19)
		)
		(stroke
			(width 0)
			(type default)
		)
	)
	(wire
		(pts
			(xy 144.78 163.83) (xy 143.51 163.83)
		)
		(stroke
			(width 0)
			(type default)
		)
	)
	(wire
		(pts
			(xy 271.78 52.07) (xy 293.37 52.07)
		)
		(stroke
			(width 0)
			(type default)
		)
	)
	(wire
		(pts
			(xy 353.06 69.85) (xy 354.33 69.85)
		)
		(stroke
			(width 0)
			(type default)
		)
	)
	(wire
		(pts
			(xy 213.36 176.53) (xy 212.09 176.53)
		)
		(stroke
			(width 0)
			(type default)
		)
	)
	(wire
		(pts
			(xy 379.73 205.74) (xy 379.73 204.47)
		)
		(stroke
			(width 0)
			(type default)
		)
	)
	(wire
		(pts
			(xy 237.49 171.45) (xy 237.49 173.99)
		)
		(stroke
			(width 0)
			(type default)
		)
	)
	(wire
		(pts
			(xy 237.49 245.11) (xy 237.49 252.73)
		)
		(stroke
			(width 0)
			(type default)
		)
	)
	(wire
		(pts
			(xy 247.65 74.93) (xy 247.65 82.55)
		)
		(stroke
			(width 0)
			(type default)
		)
	)
	(wire
		(pts
			(xy 212.09 179.07) (xy 212.09 186.69)
		)
		(stroke
			(width 0)
			(type default)
		)
	)
	(wire
		(pts
			(xy 81.28 196.85) (xy 82.55 196.85)
		)
		(stroke
			(width 0)
			(type default)
		)
	)
	(wire
		(pts
			(xy 247.65 52.07) (xy 247.65 59.69)
		)
		(stroke
			(width 0)
			(type default)
		)
	)
	(wire
		(pts
			(xy 208.28 245.11) (xy 210.82 242.57)
		)
		(stroke
			(width 0)
			(type default)
		)
	)
	(wire
		(pts
			(xy 191.77 77.47) (xy 191.77 85.09)
		)
		(stroke
			(width 0)
			(type default)
		)
	)
	(wire
		(pts
			(xy 191.77 128.27) (xy 191.77 129.54)
		)
		(stroke
			(width 0)
			(type default)
		)
	)
	(wire
		(pts
			(xy 191.77 92.71) (xy 191.77 100.33)
		)
		(stroke
			(width 0)
			(type default)
		)
	)
	(bus
		(pts
			(xy 232.41 53.34) (xy 232.41 55.88)
		)
		(stroke
			(width 0)
			(type default)
		)
	)
	(wire
		(pts
			(xy 358.14 236.22) (xy 358.14 234.95)
		)
		(stroke
			(width 0)
			(type default)
		)
	)
	(wire
		(pts
			(xy 271.78 49.53) (xy 273.05 49.53)
		)
		(stroke
			(width 0)
			(type default)
		)
	)
	(wire
		(pts
			(xy 248.92 90.17) (xy 247.65 90.17)
		)
		(stroke
			(width 0)
			(type default)
		)
	)
	(wire
		(pts
			(xy 82.55 247.65) (xy 81.28 247.65)
		)
		(stroke
			(width 0)
			(type default)
		)
	)
	(bus
		(pts
			(xy 196.85 190.5) (xy 196.85 193.04)
		)
		(stroke
			(width 0)
			(type default)
		)
	)
	(wire
		(pts
			(xy 80.01 31.75) (xy 72.39 31.75)
		)
		(stroke
			(width 0)
			(type default)
		)
	)
	(wire
		(pts
			(xy 109.22 105.41) (xy 127 105.41)
		)
		(stroke
			(width 0)
			(type default)
		)
	)
	(wire
		(pts
			(xy 358.14 185.42) (xy 358.14 186.69)
		)
		(stroke
			(width 0)
			(type default)
		)
	)
	(wire
		(pts
			(xy 191.77 100.33) (xy 191.77 107.95)
		)
		(stroke
			(width 0)
			(type default)
		)
	)
	(wire
		(pts
			(xy 110.49 46.99) (xy 110.49 54.61)
		)
		(stroke
			(width 0)
			(type default)
		)
	)
	(wire
		(pts
			(xy 213.36 153.67) (xy 204.47 153.67)
		)
		(stroke
			(width 0)
			(type default)
		)
	)
	(wire
		(pts
			(xy 213.36 199.39) (xy 212.09 199.39)
		)
		(stroke
			(width 0)
			(type default)
		)
	)
	(wire
		(pts
			(xy 190.5 29.21) (xy 191.77 29.21)
		)
		(stroke
			(width 0)
			(type default)
		)
	)
	(wire
		(pts
			(xy 271.78 57.15) (xy 273.05 57.15)
		)
		(stroke
			(width 0)
			(type default)
		)
	)
	(wire
		(pts
			(xy 81.28 189.23) (xy 82.55 189.23)
		)
		(stroke
			(width 0)
			(type default)
		)
	)
	(wire
		(pts
			(xy 198.12 245.11) (xy 208.28 245.11)
		)
		(stroke
			(width 0)
			(type default)
		)
	)
	(wire
		(pts
			(xy 248.92 69.85) (xy 233.68 69.85)
		)
		(stroke
			(width 0)
			(type default)
		)
	)
	(wire
		(pts
			(xy 241.3 219.71) (xy 238.76 217.17)
		)
		(stroke
			(width 0)
			(type default)
		)
	)
	(wire
		(pts
			(xy 353.06 100.33) (xy 354.33 100.33)
		)
		(stroke
			(width 0)
			(type default)
		)
	)
	(wire
		(pts
			(xy 166.37 110.49) (xy 166.37 118.11)
		)
		(stroke
			(width 0)
			(type default)
		)
	)
	(wire
		(pts
			(xy 191.77 123.19) (xy 190.5 123.19)
		)
		(stroke
			(width 0)
			(type default)
		)
	)
	(wire
		(pts
			(xy 236.22 181.61) (xy 237.49 181.61)
		)
		(stroke
			(width 0)
			(type default)
		)
	)
	(bus
		(pts
			(xy 232.41 76.2) (xy 232.41 78.74)
		)
		(stroke
			(width 0)
			(type default)
		)
	)
	(wire
		(pts
			(xy 85.09 110.49) (xy 86.36 110.49)
		)
		(stroke
			(width 0)
			(type default)
		)
	)
	(wire
		(pts
			(xy 387.35 205.74) (xy 397.51 205.74)
		)
		(stroke
			(width 0)
			(type default)
		)
	)
	(bus
		(pts
			(xy 289.56 226.06) (xy 289.56 228.6)
		)
		(stroke
			(width 0)
			(type default)
		)
	)
	(wire
		(pts
			(xy 328.93 34.29) (xy 328.93 41.91)
		)
		(stroke
			(width 0)
			(type default)
		)
	)
	(wire
		(pts
			(xy 81.28 217.17) (xy 82.55 217.17)
		)
		(stroke
			(width 0)
			(type default)
		)
	)
	(wire
		(pts
			(xy 264.16 237.49) (xy 241.3 237.49)
		)
		(stroke
			(width 0)
			(type default)
		)
	)
	(wire
		(pts
			(xy 393.7 185.42) (xy 393.7 187.96)
		)
		(stroke
			(width 0)
			(type default)
		)
	)
	(wire
		(pts
			(xy 213.36 227.33) (xy 212.09 227.33)
		)
		(stroke
			(width 0)
			(type default)
		)
	)
	(wire
		(pts
			(xy 109.22 74.93) (xy 127 74.93)
		)
		(stroke
			(width 0)
			(type default)
		)
	)
	(wire
		(pts
			(xy 119.38 158.75) (xy 120.65 158.75)
		)
		(stroke
			(width 0)
			(type default)
		)
	)
	(wire
		(pts
			(xy 181.61 149.86) (xy 181.61 153.67)
		)
		(stroke
			(width 0)
			(type default)
		)
	)
	(wire
		(pts
			(xy 110.49 77.47) (xy 110.49 85.09)
		)
		(stroke
			(width 0)
			(type default)
		)
	)
	(wire
		(pts
			(xy 248.92 72.39) (xy 233.68 72.39)
		)
		(stroke
			(width 0)
			(type default)
		)
	)
	(wire
		(pts
			(xy 144.78 240.03) (xy 144.78 247.65)
		)
		(stroke
			(width 0)
			(type default)
		)
	)
	(wire
		(pts
			(xy 271.78 59.69) (xy 273.05 59.69)
		)
		(stroke
			(width 0)
			(type default)
		)
	)
	(wire
		(pts
			(xy 120.65 250.19) (xy 119.38 250.19)
		)
		(stroke
			(width 0)
			(type default)
		)
	)
	(wire
		(pts
			(xy 330.2 102.87) (xy 328.93 102.87)
		)
		(stroke
			(width 0)
			(type default)
		)
	)
	(wire
		(pts
			(xy 212.09 247.65) (xy 213.36 247.65)
		)
		(stroke
			(width 0)
			(type default)
		)
	)
	(wire
		(pts
			(xy 57.15 181.61) (xy 57.15 184.15)
		)
		(stroke
			(width 0)
			(type default)
		)
	)
	(wire
		(pts
			(xy 354.33 129.54) (xy 354.33 128.27)
		)
		(stroke
			(width 0)
			(type default)
		)
	)
	(wire
		(pts
			(xy 198.12 181.61) (xy 213.36 181.61)
		)
		(stroke
			(width 0)
			(type default)
		)
	)
	(wire
		(pts
			(xy 81.28 229.87) (xy 82.55 229.87)
		)
		(stroke
			(width 0)
			(type default)
		)
	)
	(wire
		(pts
			(xy 166.37 118.11) (xy 167.64 118.11)
		)
		(stroke
			(width 0)
			(type default)
		)
	)
	(wire
		(pts
			(xy 86.36 62.23) (xy 71.12 62.23)
		)
		(stroke
			(width 0)
			(type default)
		)
	)
	(wire
		(pts
			(xy 110.49 92.71) (xy 110.49 100.33)
		)
		(stroke
			(width 0)
			(type default)
		)
	)
	(wire
		(pts
			(xy 191.77 100.33) (xy 190.5 100.33)
		)
		(stroke
			(width 0)
			(type default)
		)
	)
	(wire
		(pts
			(xy 368.3 31.75) (xy 353.06 31.75)
		)
		(stroke
			(width 0)
			(type default)
		)
	)
	(wire
		(pts
			(xy 251.46 179.07) (xy 236.22 179.07)
		)
		(stroke
			(width 0)
			(type default)
		)
	)
	(wire
		(pts
			(xy 285.75 115.57) (xy 275.59 115.57)
		)
		(stroke
			(width 0)
			(type default)
		)
	)
	(bus
		(pts
			(xy 232.41 83.82) (xy 231.14 82.55)
		)
		(stroke
			(width 0)
			(type default)
		)
	)
	(wire
		(pts
			(xy 353.06 36.83) (xy 354.33 36.83)
		)
		(stroke
			(width 0)
			(type default)
		)
	)
	(wire
		(pts
			(xy 270.51 247.65) (xy 269.24 247.65)
		)
		(stroke
			(width 0)
			(type default)
		)
	)
	(wire
		(pts
			(xy 97.79 242.57) (xy 97.79 243.84)
		)
		(stroke
			(width 0)
			(type default)
		)
	)
	(wire
		(pts
			(xy 247.65 34.29) (xy 247.65 41.91)
		)
		(stroke
			(width 0)
			(type default)
		)
	)
	(wire
		(pts
			(xy 358.14 175.26) (xy 358.14 176.53)
		)
		(stroke
			(width 0)
			(type default)
		)
	)
	(wire
		(pts
			(xy 127 90.17) (xy 109.22 90.17)
		)
		(stroke
			(width 0)
			(type default)
		)
	)
	(bus
		(pts
			(xy 313.69 35.56) (xy 313.69 38.1)
		)
		(stroke
			(width 0)
			(type default)
		)
	)
	(wire
		(pts
			(xy 119.38 166.37) (xy 120.65 166.37)
		)
		(stroke
			(width 0)
			(type default)
		)
	)
	(wire
		(pts
			(xy 387.35 196.85) (xy 397.51 196.85)
		)
		(stroke
			(width 0)
			(type default)
		)
	)
	(bus
		(pts
			(xy 295.91 59.69) (xy 294.64 60.96)
		)
		(stroke
			(width 0)
			(type default)
		)
	)
	(bus
		(pts
			(xy 288.29 71.12) (xy 289.56 69.85)
		)
		(stroke
			(width 0)
			(type default)
		)
	)
	(wire
		(pts
			(xy 85.09 72.39) (xy 86.36 72.39)
		)
		(stroke
			(width 0)
			(type default)
		)
	)
	(wire
		(pts
			(xy 144.78 252.73) (xy 143.51 252.73)
		)
		(stroke
			(width 0)
			(type default)
		)
	)
	(wire
		(pts
			(xy 247.65 31.75) (xy 247.65 34.29)
		)
		(stroke
			(width 0)
			(type default)
		)
	)
	(wire
		(pts
			(xy 208.28 232.41) (xy 210.82 234.95)
		)
		(stroke
			(width 0)
			(type default)
		)
	)
	(wire
		(pts
			(xy 238.76 229.87) (xy 236.22 229.87)
		)
		(stroke
			(width 0)
			(type default)
		)
	)
	(wire
		(pts
			(xy 353.06 87.63) (xy 354.33 87.63)
		)
		(stroke
			(width 0)
			(type default)
		)
	)
	(wire
		(pts
			(xy 368.3 72.39) (xy 353.06 72.39)
		)
		(stroke
			(width 0)
			(type default)
		)
	)
	(wire
		(pts
			(xy 81.28 153.67) (xy 83.82 153.67)
		)
		(stroke
			(width 0)
			(type default)
		)
	)
	(wire
		(pts
			(xy 58.42 222.25) (xy 57.15 222.25)
		)
		(stroke
			(width 0)
			(type default)
		)
	)
	(bus
		(pts
			(xy 297.18 59.69) (xy 295.91 59.69)
		)
		(stroke
			(width 0)
			(type default)
		)
	)
	(bus
		(pts
			(xy 252.73 177.8) (xy 252.73 185.42)
		)
		(stroke
			(width 0)
			(type default)
		)
	)
	(wire
		(pts
			(xy 82.55 219.71) (xy 82.55 227.33)
		)
		(stroke
			(width 0)
			(type default)
		)
	)
	(bus
		(pts
			(xy 130.81 40.64) (xy 130.81 43.18)
		)
		(stroke
			(width 0)
			(type default)
		)
	)
	(wire
		(pts
			(xy 212.09 158.75) (xy 212.09 166.37)
		)
		(stroke
			(width 0)
			(type default)
		)
	)
	(wire
		(pts
			(xy 86.36 252.73) (xy 81.28 252.73)
		)
		(stroke
			(width 0)
			(type default)
		)
	)
	(wire
		(pts
			(xy 270.51 247.65) (xy 273.05 250.19)
		)
		(stroke
			(width 0)
			(type default)
		)
	)
	(wire
		(pts
			(xy 57.15 222.25) (xy 57.15 224.79)
		)
		(stroke
			(width 0)
			(type default)
		)
	)
	(wire
		(pts
			(xy 81.28 207.01) (xy 82.55 207.01)
		)
		(stroke
			(width 0)
			(type default)
		)
	)
	(wire
		(pts
			(xy 210.82 232.41) (xy 213.36 232.41)
		)
		(stroke
			(width 0)
			(type default)
		)
	)
	(wire
		(pts
			(xy 85.09 95.25) (xy 86.36 95.25)
		)
		(stroke
			(width 0)
			(type default)
		)
	)
	(wire
		(pts
			(xy 236.22 194.31) (xy 237.49 194.31)
		)
		(stroke
			(width 0)
			(type default)
		)
	)
	(wire
		(pts
			(xy 166.37 49.53) (xy 167.64 49.53)
		)
		(stroke
			(width 0)
			(type default)
		)
	)
	(bus
		(pts
			(xy 66.04 57.15) (xy 68.58 57.15)
		)
		(stroke
			(width 0)
			(type default)
		)
	)
	(wire
		(pts
			(xy 85.09 41.91) (xy 86.36 41.91)
		)
		(stroke
			(width 0)
			(type default)
		)
	)
	(wire
		(pts
			(xy 377.19 180.34) (xy 384.81 180.34)
		)
		(stroke
			(width 0)
			(type default)
		)
	)
	(wire
		(pts
			(xy 109.22 29.21) (xy 110.49 29.21)
		)
		(stroke
			(width 0)
			(type default)
		)
	)
	(wire
		(pts
			(xy 241.3 227.33) (xy 238.76 229.87)
		)
		(stroke
			(width 0)
			(type default)
		)
	)
	(wire
		(pts
			(xy 144.78 179.07) (xy 143.51 179.07)
		)
		(stroke
			(width 0)
			(type default)
		)
	)
	(wire
		(pts
			(xy 248.92 128.27) (xy 245.11 128.27)
		)
		(stroke
			(width 0)
			(type default)
		)
	)
	(wire
		(pts
			(xy 330.2 44.45) (xy 328.93 44.45)
		)
		(stroke
			(width 0)
			(type default)
		)
	)
	(wire
		(pts
			(xy 166.37 80.01) (xy 166.37 87.63)
		)
		(stroke
			(width 0)
			(type default)
		)
	)
	(bus
		(pts
			(xy 297.18 49.53) (xy 295.91 49.53)
		)
		(stroke
			(width 0)
			(type default)
		)
	)
	(wire
		(pts
			(xy 233.68 92.71) (xy 248.92 92.71)
		)
		(stroke
			(width 0)
			(type default)
		)
	)
	(wire
		(pts
			(xy 213.36 229.87) (xy 212.09 229.87)
		)
		(stroke
			(width 0)
			(type default)
		)
	)
	(wire
		(pts
			(xy 288.29 240.03) (xy 261.62 240.03)
		)
		(stroke
			(width 0)
			(type default)
		)
	)
	(wire
		(pts
			(xy 349.25 236.22) (xy 349.25 234.95)
		)
		(stroke
			(width 0)
			(type default)
		)
	)
	(wire
		(pts
			(xy 382.27 215.9) (xy 379.73 215.9)
		)
		(stroke
			(width 0)
			(type default)
		)
	)
	(wire
		(pts
			(xy 271.78 100.33) (xy 273.05 100.33)
		)
		(stroke
			(width 0)
			(type default)
		)
	)
	(wire
		(pts
			(xy 314.96 69.85) (xy 330.2 69.85)
		)
		(stroke
			(width 0)
			(type default)
		)
	)
	(wire
		(pts
			(xy 213.36 168.91) (xy 212.09 168.91)
		)
		(stroke
			(width 0)
			(type default)
		)
	)
	(wire
		(pts
			(xy 328.93 52.07) (xy 328.93 54.61)
		)
		(stroke
			(width 0)
			(type default)
		)
	)
	(wire
		(pts
			(xy 85.09 118.11) (xy 85.09 125.73)
		)
		(stroke
			(width 0)
			(type default)
		)
	)
	(wire
		(pts
			(xy 273.05 57.15) (xy 273.05 59.69)
		)
		(stroke
			(width 0)
			(type default)
		)
	)
	(wire
		(pts
			(xy 119.38 242.57) (xy 120.65 242.57)
		)
		(stroke
			(width 0)
			(type default)
		)
	)
	(wire
		(pts
			(xy 339.09 228.6) (xy 337.82 228.6)
		)
		(stroke
			(width 0)
			(type default)
		)
	)
	(wire
		(pts
			(xy 144.78 186.69) (xy 144.78 194.31)
		)
		(stroke
			(width 0)
			(type default)
		)
	)
	(bus
		(pts
			(xy 130.81 63.5) (xy 130.81 66.04)
		)
		(stroke
			(width 0)
			(type default)
		)
	)
	(wire
		(pts
			(xy 271.78 77.47) (xy 273.05 77.47)
		)
		(stroke
			(width 0)
			(type default)
		)
	)
	(wire
		(pts
			(xy 191.77 115.57) (xy 190.5 115.57)
		)
		(stroke
			(width 0)
			(type default)
		)
	)
	(wire
		(pts
			(xy 58.42 242.57) (xy 57.15 242.57)
		)
		(stroke
			(width 0)
			(type default)
		)
	)
	(wire
		(pts
			(xy 379.73 196.85) (xy 382.27 196.85)
		)
		(stroke
			(width 0)
			(type default)
		)
	)
	(wire
		(pts
			(xy 119.38 166.37) (xy 119.38 173.99)
		)
		(stroke
			(width 0)
			(type default)
		)
	)
	(wire
		(pts
			(xy 328.93 115.57) (xy 328.93 123.19)
		)
		(stroke
			(width 0)
			(type default)
		)
	)
	(wire
		(pts
			(xy 81.28 176.53) (xy 82.55 176.53)
		)
		(stroke
			(width 0)
			(type default)
		)
	)
	(wire
		(pts
			(xy 191.77 39.37) (xy 190.5 39.37)
		)
		(stroke
			(width 0)
			(type default)
		)
	)
	(bus
		(pts
			(xy 369.57 30.48) (xy 369.57 33.02)
		)
		(stroke
			(width 0)
			(type default)
		)
	)
	(wire
		(pts
			(xy 330.2 85.09) (xy 328.93 85.09)
		)
		(stroke
			(width 0)
			(type default)
		)
	)
	(wire
		(pts
			(xy 212.09 209.55) (xy 212.09 217.17)
		)
		(stroke
			(width 0)
			(type default)
		)
	)
	(wire
		(pts
			(xy 236.22 191.77) (xy 237.49 191.77)
		)
		(stroke
			(width 0)
			(type default)
		)
	)
	(wire
		(pts
			(xy 248.92 54.61) (xy 233.68 54.61)
		)
		(stroke
			(width 0)
			(type default)
		)
	)
	(wire
		(pts
			(xy 85.09 34.29) (xy 85.09 41.91)
		)
		(stroke
			(width 0)
			(type default)
		)
	)
	(wire
		(pts
			(xy 110.49 77.47) (xy 109.22 77.47)
		)
		(stroke
			(width 0)
			(type default)
		)
	)
	(wire
		(pts
			(xy 213.36 196.85) (xy 212.09 196.85)
		)
		(stroke
			(width 0)
			(type default)
		)
	)
	(wire
		(pts
			(xy 330.2 36.83) (xy 314.96 36.83)
		)
		(stroke
			(width 0)
			(type default)
		)
	)
	(wire
		(pts
			(xy 198.12 191.77) (xy 213.36 191.77)
		)
		(stroke
			(width 0)
			(type default)
		)
	)
	(bus
		(pts
			(xy 228.6 82.55) (xy 231.14 82.55)
		)
		(stroke
			(width 0)
			(type default)
		)
	)
	(wire
		(pts
			(xy 85.09 118.11) (xy 86.36 118.11)
		)
		(stroke
			(width 0)
			(type default)
		)
	)
	(wire
		(pts
			(xy 58.42 224.79) (xy 57.15 224.79)
		)
		(stroke
			(width 0)
			(type default)
		)
	)
	(wire
		(pts
			(xy 85.09 64.77) (xy 86.36 64.77)
		)
		(stroke
			(width 0)
			(type default)
		)
	)
	(wire
		(pts
			(xy 382.27 246.38) (xy 379.73 246.38)
		)
		(stroke
			(width 0)
			(type default)
		)
	)
	(wire
		(pts
			(xy 119.38 156.21) (xy 120.65 156.21)
		)
		(stroke
			(width 0)
			(type default)
		)
	)
	(wire
		(pts
			(xy 288.29 229.87) (xy 241.3 229.87)
		)
		(stroke
			(width 0)
			(type default)
		)
	)
	(wire
		(pts
			(xy 191.77 153.67) (xy 190.5 153.67)
		)
		(stroke
			(width 0)
			(type default)
		)
	)
	(wire
		(pts
			(xy 330.2 105.41) (xy 328.93 105.41)
		)
		(stroke
			(width 0)
			(type default)
		)
	)
	(wire
		(pts
			(xy 247.65 90.17) (xy 247.65 97.79)
		)
		(stroke
			(width 0)
			(type default)
		)
	)
	(wire
		(pts
			(xy 144.78 201.93) (xy 143.51 201.93)
		)
		(stroke
			(width 0)
			(type default)
		)
	)
	(bus
		(pts
			(xy 369.57 40.64) (xy 369.57 43.18)
		)
		(stroke
			(width 0)
			(type default)
		)
	)
	(wire
		(pts
			(xy 110.49 128.27) (xy 109.22 128.27)
		)
		(stroke
			(width 0)
			(type default)
		)
	)
	(wire
		(pts
			(xy 185.42 153.67) (xy 181.61 153.67)
		)
		(stroke
			(width 0)
			(type default)
		)
	)
	(wire
		(pts
			(xy 339.09 238.76) (xy 339.09 236.22)
		)
		(stroke
			(width 0)
			(type default)
		)
	)
	(bus
		(pts
			(xy 295.91 49.53) (xy 294.64 50.8)
		)
		(stroke
			(width 0)
			(type default)
		)
	)
	(wire
		(pts
			(xy 110.49 54.61) (xy 109.22 54.61)
		)
		(stroke
			(width 0)
			(type default)
		)
	)
	(wire
		(pts
			(xy 236.22 224.79) (xy 237.49 224.79)
		)
		(stroke
			(width 0)
			(type default)
		)
	)
	(wire
		(pts
			(xy 271.78 110.49) (xy 273.05 110.49)
		)
		(stroke
			(width 0)
			(type default)
		)
	)
	(wire
		(pts
			(xy 354.33 118.11) (xy 354.33 120.65)
		)
		(stroke
			(width 0)
			(type default)
		)
	)
	(bus
		(pts
			(xy 313.69 45.72) (xy 313.69 48.26)
		)
		(stroke
			(width 0)
			(type default)
		)
	)
	(wire
		(pts
			(xy 271.78 80.01) (xy 273.05 80.01)
		)
		(stroke
			(width 0)
			(type default)
		)
	)
	(wire
		(pts
			(xy 127 97.79) (xy 109.22 97.79)
		)
		(stroke
			(width 0)
			(type default)
		)
	)
	(bus
		(pts
			(xy 172.72 223.52) (xy 172.72 231.14)
		)
		(stroke
			(width 0)
			(type default)
		)
	)
	(wire
		(pts
			(xy 354.33 57.15) (xy 354.33 59.69)
		)
		(stroke
			(width 0)
			(type default)
		)
	)
	(bus
		(pts
			(xy 288.29 73.66) (xy 289.56 72.39)
		)
		(stroke
			(width 0)
			(type default)
		)
	)
	(wire
		(pts
			(xy 287.02 82.55) (xy 271.78 82.55)
		)
		(stroke
			(width 0)
			(type default)
		)
	)
	(bus
		(pts
			(xy 172.72 241.3) (xy 172.72 243.84)
		)
		(stroke
			(width 0)
			(type default)
		)
	)
	(wire
		(pts
			(xy 271.78 46.99) (xy 273.05 46.99)
		)
		(stroke
			(width 0)
			(type default)
		)
	)
	(wire
		(pts
			(xy 271.78 123.19) (xy 273.05 123.19)
		)
		(stroke
			(width 0)
			(type default)
		)
	)
	(wire
		(pts
			(xy 368.3 62.23) (xy 353.06 62.23)
		)
		(stroke
			(width 0)
			(type default)
		)
	)
	(wire
		(pts
			(xy 354.33 59.69) (xy 354.33 67.31)
		)
		(stroke
			(width 0)
			(type default)
		)
	)
	(wire
		(pts
			(xy 58.42 194.31) (xy 57.15 194.31)
		)
		(stroke
			(width 0)
			(type default)
		)
	)
	(bus
		(pts
			(xy 289.56 246.38) (xy 289.56 248.92)
		)
		(stroke
			(width 0)
			(type default)
		)
	)
	(wire
		(pts
			(xy 110.49 92.71) (xy 109.22 92.71)
		)
		(stroke
			(width 0)
			(type default)
		)
	)
	(wire
		(pts
			(xy 81.28 234.95) (xy 83.82 234.95)
		)
		(stroke
			(width 0)
			(type default)
		)
	)
	(bus
		(pts
			(xy 66.04 49.53) (xy 68.58 49.53)
		)
		(stroke
			(width 0)
			(type default)
		)
	)
	(wire
		(pts
			(xy 58.42 201.93) (xy 57.15 201.93)
		)
		(stroke
			(width 0)
			(type default)
		)
	)
	(wire
		(pts
			(xy 288.29 227.33) (xy 241.3 227.33)
		)
		(stroke
			(width 0)
			(type default)
		)
	)
	(wire
		(pts
			(xy 245.11 128.27) (xy 245.11 123.19)
		)
		(stroke
			(width 0)
			(type default)
		)
	)
	(wire
		(pts
			(xy 237.49 252.73) (xy 236.22 252.73)
		)
		(stroke
			(width 0)
			(type default)
		)
	)
	(wire
		(pts
			(xy 330.2 92.71) (xy 328.93 92.71)
		)
		(stroke
			(width 0)
			(type default)
		)
	)
	(wire
		(pts
			(xy 110.49 128.27) (xy 110.49 129.54)
		)
		(stroke
			(width 0)
			(type default)
		)
	)
	(wire
		(pts
			(xy 86.36 242.57) (xy 81.28 242.57)
		)
		(stroke
			(width 0)
			(type default)
		)
	)
	(bus
		(pts
			(xy 130.81 43.18) (xy 130.81 48.26)
		)
		(stroke
			(width 0)
			(type default)
		)
	)
	(wire
		(pts
			(xy 328.93 82.55) (xy 328.93 85.09)
		)
		(stroke
			(width 0)
			(type default)
		)
	)
	(wire
		(pts
			(xy 191.77 107.95) (xy 191.77 115.57)
		)
		(stroke
			(width 0)
			(type default)
		)
	)
	(wire
		(pts
			(xy 167.64 125.73) (xy 166.37 125.73)
		)
		(stroke
			(width 0)
			(type default)
		)
	)
	(wire
		(pts
			(xy 110.49 39.37) (xy 110.49 46.99)
		)
		(stroke
			(width 0)
			(type default)
		)
	)
	(bus
		(pts
			(xy 64.77 73.66) (xy 64.77 76.2)
		)
		(stroke
			(width 0)
			(type default)
		)
	)
	(wire
		(pts
			(xy 248.92 34.29) (xy 247.65 34.29)
		)
		(stroke
			(width 0)
			(type default)
		)
	)
	(wire
		(pts
			(xy 238.76 240.03) (xy 236.22 240.03)
		)
		(stroke
			(width 0)
			(type default)
		)
	)
	(wire
		(pts
			(xy 166.37 72.39) (xy 167.64 72.39)
		)
		(stroke
			(width 0)
			(type default)
		)
	)
	(wire
		(pts
			(xy 248.92 67.31) (xy 247.65 67.31)
		)
		(stroke
			(width 0)
			(type default)
		)
	)
	(wire
		(pts
			(xy 339.09 233.68) (xy 337.82 233.68)
		)
		(stroke
			(width 0)
			(type default)
		)
	)
	(wire
		(pts
			(xy 81.28 168.91) (xy 82.55 168.91)
		)
		(stroke
			(width 0)
			(type default)
		)
	)
	(wire
		(pts
			(xy 86.36 107.95) (xy 66.04 107.95)
		)
		(stroke
			(width 0)
			(type default)
		)
	)
	(bus
		(pts
			(xy 129.54 102.87) (xy 128.27 104.14)
		)
		(stroke
			(width 0)
			(type default)
		)
	)
	(wire
		(pts
			(xy 82.55 166.37) (xy 82.55 168.91)
		)
		(stroke
			(width 0)
			(type default)
		)
	)
	(wire
		(pts
			(xy 328.93 105.41) (xy 328.93 113.03)
		)
		(stroke
			(width 0)
			(type default)
		)
	)
	(wire
		(pts
			(xy 58.42 245.11) (xy 57.15 245.11)
		)
		(stroke
			(width 0)
			(type default)
		)
	)
	(wire
		(pts
			(xy 248.92 46.99) (xy 233.68 46.99)
		)
		(stroke
			(width 0)
			(type default)
		)
	)
	(wire
		(pts
			(xy 110.49 100.33) (xy 109.22 100.33)
		)
		(stroke
			(width 0)
			(type default)
		)
	)
	(wire
		(pts
			(xy 237.49 173.99) (xy 237.49 181.61)
		)
		(stroke
			(width 0)
			(type default)
		)
	)
	(wire
		(pts
			(xy 110.49 107.95) (xy 110.49 115.57)
		)
		(stroke
			(width 0)
			(type default)
		)
	)
	(wire
		(pts
			(xy 81.28 166.37) (xy 82.55 166.37)
		)
		(stroke
			(width 0)
			(type default)
		)
	)
	(wire
		(pts
			(xy 212.09 176.53) (xy 212.09 179.07)
		)
		(stroke
			(width 0)
			(type default)
		)
	)
	(bus
		(pts
			(xy 172.72 233.68) (xy 172.72 241.3)
		)
		(stroke
			(width 0)
			(type default)
		)
	)
	(wire
		(pts
			(xy 82.55 168.91) (xy 82.55 176.53)
		)
		(stroke
			(width 0)
			(type default)
		)
	)
	(wire
		(pts
			(xy 349.25 228.6) (xy 349.25 229.87)
		)
		(stroke
			(width 0)
			(type default)
		)
	)
	(wire
		(pts
			(xy 287.02 72.39) (xy 271.78 72.39)
		)
		(stroke
			(width 0)
			(type default)
		)
	)
	(bus
		(pts
			(xy 128.27 78.74) (xy 128.27 81.28)
		)
		(stroke
			(width 0)
			(type default)
		)
	)
	(bus
		(pts
			(xy 231.14 90.17) (xy 232.41 91.44)
		)
		(stroke
			(width 0)
			(type default)
		)
	)
	(wire
		(pts
			(xy 248.92 52.07) (xy 247.65 52.07)
		)
		(stroke
			(width 0)
			(type default)
		)
	)
	(wire
		(pts
			(xy 237.49 194.31) (xy 237.49 201.93)
		)
		(stroke
			(width 0)
			(type default)
		)
	)
	(wire
		(pts
			(xy 144.78 217.17) (xy 143.51 217.17)
		)
		(stroke
			(width 0)
			(type default)
		)
	)
	(wire
		(pts
			(xy 191.77 36.83) (xy 191.77 39.37)
		)
		(stroke
			(width 0)
			(type default)
		)
	)
	(bus
		(pts
			(xy 129.54 87.63) (xy 128.27 88.9)
		)
		(stroke
			(width 0)
			(type default)
		)
	)
	(wire
		(pts
			(xy 144.78 209.55) (xy 144.78 217.17)
		)
		(stroke
			(width 0)
			(type default)
		)
	)
	(wire
		(pts
			(xy 330.2 128.27) (xy 327.66 128.27)
		)
		(stroke
			(width 0)
			(type default)
		)
	)
	(wire
		(pts
			(xy 86.36 92.71) (xy 66.04 92.71)
		)
		(stroke
			(width 0)
			(type default)
		)
	)
	(wire
		(pts
			(xy 238.76 227.33) (xy 236.22 227.33)
		)
		(stroke
			(width 0)
			(type default)
		)
	)
	(wire
		(pts
			(xy 166.37 64.77) (xy 167.64 64.77)
		)
		(stroke
			(width 0)
			(type default)
		)
	)
	(wire
		(pts
			(xy 166.37 95.25) (xy 167.64 95.25)
		)
		(stroke
			(width 0)
			(type default)
		)
	)
	(wire
		(pts
			(xy 353.06 110.49) (xy 354.33 110.49)
		)
		(stroke
			(width 0)
			(type default)
		)
	)
	(wire
		(pts
			(xy 213.36 186.69) (xy 212.09 186.69)
		)
		(stroke
			(width 0)
			(type default)
		)
	)
	(wire
		(pts
			(xy 251.46 196.85) (xy 236.22 196.85)
		)
		(stroke
			(width 0)
			(type default)
		)
	)
	(wire
		(pts
			(xy 198.12 184.15) (xy 213.36 184.15)
		)
		(stroke
			(width 0)
			(type default)
		)
	)
	(wire
		(pts
			(xy 144.78 161.29) (xy 143.51 161.29)
		)
		(stroke
			(width 0)
			(type default)
		)
	)
	(wire
		(pts
			(xy 314.96 59.69) (xy 330.2 59.69)
		)
		(stroke
			(width 0)
			(type default)
		)
	)
	(wire
		(pts
			(xy 314.96 57.15) (xy 330.2 57.15)
		)
		(stroke
			(width 0)
			(type default)
		)
	)
	(wire
		(pts
			(xy 58.42 191.77) (xy 57.15 191.77)
		)
		(stroke
			(width 0)
			(type default)
		)
	)
	(wire
		(pts
			(xy 353.06 187.96) (xy 353.06 189.23)
		)
		(stroke
			(width 0)
			(type default)
		)
	)
	(bus
		(pts
			(xy 369.57 43.18) (xy 369.57 50.8)
		)
		(stroke
			(width 0)
			(type default)
		)
	)
	(wire
		(pts
			(xy 273.05 77.47) (xy 273.05 80.01)
		)
		(stroke
			(width 0)
			(type default)
		)
	)
	(wire
		(pts
			(xy 379.73 246.38) (xy 379.73 245.11)
		)
		(stroke
			(width 0)
			(type default)
		)
	)
	(bus
		(pts
			(xy 130.81 87.63) (xy 129.54 87.63)
		)
		(stroke
			(width 0)
			(type default)
		)
	)
	(wire
		(pts
			(xy 194.31 222.25) (xy 213.36 222.25)
		)
		(stroke
			(width 0)
			(type default)
		)
	)
	(wire
		(pts
			(xy 86.36 100.33) (xy 66.04 100.33)
		)
		(stroke
			(width 0)
			(type default)
		)
	)
	(bus
		(pts
			(xy 232.41 91.44) (xy 232.41 93.98)
		)
		(stroke
			(width 0)
			(type default)
		)
	)
	(wire
		(pts
			(xy 119.38 227.33) (xy 119.38 234.95)
		)
		(stroke
			(width 0)
			(type default)
		)
	)
	(wire
		(pts
			(xy 82.55 247.65) (xy 82.55 250.19)
		)
		(stroke
			(width 0)
			(type default)
		)
	)
	(wire
		(pts
			(xy 86.36 245.11) (xy 81.28 245.11)
		)
		(stroke
			(width 0)
			(type default)
		)
	)
	(wire
		(pts
			(xy 191.77 36.83) (xy 190.5 36.83)
		)
		(stroke
			(width 0)
			(type default)
		)
	)
	(wire
		(pts
			(xy 166.37 125.73) (xy 166.37 129.54)
		)
		(stroke
			(width 0)
			(type default)
		)
	)
	(wire
		(pts
			(xy 110.49 46.99) (xy 109.22 46.99)
		)
		(stroke
			(width 0)
			(type default)
		)
	)
	(wire
		(pts
			(xy 82.55 199.39) (xy 82.55 207.01)
		)
		(stroke
			(width 0)
			(type default)
		)
	)
	(wire
		(pts
			(xy 354.33 46.99) (xy 354.33 49.53)
		)
		(stroke
			(width 0)
			(type default)
		)
	)
	(bus
		(pts
			(xy 289.56 205.74) (xy 289.56 208.28)
		)
		(stroke
			(width 0)
			(type default)
		)
	)
	(wire
		(pts
			(xy 57.15 242.57) (xy 57.15 245.11)
		)
		(stroke
			(width 0)
			(type default)
		)
	)
	(wire
		(pts
			(xy 81.28 240.03) (xy 82.55 240.03)
		)
		(stroke
			(width 0)
			(type default)
		)
	)
	(wire
		(pts
			(xy 191.77 128.27) (xy 190.5 128.27)
		)
		(stroke
			(width 0)
			(type default)
		)
	)
	(wire
		(pts
			(xy 337.82 238.76) (xy 339.09 238.76)
		)
		(stroke
			(width 0)
			(type default)
		)
	)
	(wire
		(pts
			(xy 213.36 240.03) (xy 212.09 240.03)
		)
		(stroke
			(width 0)
			(type default)
		)
	)
	(wire
		(pts
			(xy 204.47 153.67) (xy 191.77 153.67)
		)
		(stroke
			(width 0)
			(type default)
		)
	)
	(bus
		(pts
			(xy 288.29 81.28) (xy 289.56 80.01)
		)
		(stroke
			(width 0)
			(type default)
		)
	)
	(wire
		(pts
			(xy 81.28 179.07) (xy 82.55 179.07)
		)
		(stroke
			(width 0)
			(type default)
		)
	)
	(wire
		(pts
			(xy 166.37 118.11) (xy 166.37 125.73)
		)
		(stroke
			(width 0)
			(type default)
		)
	)
	(bus
		(pts
			(xy 289.56 236.22) (xy 289.56 238.76)
		)
		(stroke
			(width 0)
			(type default)
		)
	)
	(wire
		(pts
			(xy 110.49 100.33) (xy 110.49 107.95)
		)
		(stroke
			(width 0)
			(type default)
		)
	)
	(wire
		(pts
			(xy 110.49 54.61) (xy 110.49 62.23)
		)
		(stroke
			(width 0)
			(type default)
		)
	)
	(bus
		(pts
			(xy 289.56 100.33) (xy 287.02 100.33)
		)
		(stroke
			(width 0)
			(type default)
		)
	)
	(wire
		(pts
			(xy 273.05 69.85) (xy 273.05 77.47)
		)
		(stroke
			(width 0)
			(type default)
		)
	)
	(wire
		(pts
			(xy 58.42 173.99) (xy 57.15 173.99)
		)
		(stroke
			(width 0)
			(type default)
		)
	)
	(wire
		(pts
			(xy 288.29 219.71) (xy 241.3 219.71)
		)
		(stroke
			(width 0)
			(type default)
		)
	)
	(bus
		(pts
			(xy 313.69 48.26) (xy 313.69 55.88)
		)
		(stroke
			(width 0)
			(type default)
		)
	)
	(wire
		(pts
			(xy 213.36 207.01) (xy 212.09 207.01)
		)
		(stroke
			(width 0)
			(type default)
		)
	)
	(bus
		(pts
			(xy 292.1 203.2) (xy 290.83 203.2)
		)
		(stroke
			(width 0)
			(type default)
		)
	)
	(wire
		(pts
			(xy 119.38 189.23) (xy 119.38 196.85)
		)
		(stroke
			(width 0)
			(type default)
		)
	)
	(bus
		(pts
			(xy 289.56 238.76) (xy 289.56 246.38)
		)
		(stroke
			(width 0)
			(type default)
		)
	)
	(wire
		(pts
			(xy 191.77 115.57) (xy 191.77 123.19)
		)
		(stroke
			(width 0)
			(type default)
		)
	)
	(bus
		(pts
			(xy 313.69 55.88) (xy 313.69 58.42)
		)
		(stroke
			(width 0)
			(type default)
		)
	)
	(wire
		(pts
			(xy 212.09 207.01) (xy 212.09 209.55)
		)
		(stroke
			(width 0)
			(type default)
		)
	)
	(bus
		(pts
			(xy 69.85 66.04) (xy 69.85 68.58)
		)
		(stroke
			(width 0)
			(type default)
		)
	)
	(wire
		(pts
			(xy 354.33 49.53) (xy 354.33 57.15)
		)
		(stroke
			(width 0)
			(type default)
		)
	)
	(wire
		(pts
			(xy 129.54 64.77) (xy 109.22 64.77)
		)
		(stroke
			(width 0)
			(type default)
		)
	)
	(bus
		(pts
			(xy 172.72 231.14) (xy 172.72 233.68)
		)
		(stroke
			(width 0)
			(type default)
		)
	)
	(bus
		(pts
			(xy 196.85 180.34) (xy 196.85 182.88)
		)
		(stroke
			(width 0)
			(type default)
		)
	)
	(wire
		(pts
			(xy 119.38 196.85) (xy 120.65 196.85)
		)
		(stroke
			(width 0)
			(type default)
		)
	)
	(wire
		(pts
			(xy 57.15 173.99) (xy 57.15 181.61)
		)
		(stroke
			(width 0)
			(type default)
		)
	)
	(wire
		(pts
			(xy 236.22 204.47) (xy 237.49 204.47)
		)
		(stroke
			(width 0)
			(type default)
		)
	)
	(wire
		(pts
			(xy 354.33 100.33) (xy 354.33 107.95)
		)
		(stroke
			(width 0)
			(type default)
		)
	)
	(label "SPI3.MISO"
		(at 67.31 107.95 0)
		(effects
			(font
				(size 1.27 1.27)
			)
			(justify left bottom)
		)
	)
	(label "+VCC_FMC"
		(at 397.51 215.9 180)
		(effects
			(font
				(size 1.27 1.27)
			)
			(justify right bottom)
		)
	)
	(label "PCIe_{C2x1}.CLK+"
		(at 175.26 232.41 0)
		(effects
			(font
				(size 1.27 1.27)
			)
			(justify left bottom)
		)
	)
	(label "CAN3.DIN"
		(at 82.55 67.31 180)
		(effects
			(font
				(size 1.27 1.27)
			)
			(justify right bottom)
		)
	)
	(label "DP2.AUX-"
		(at 367.03 31.75 180)
		(effects
			(font
				(size 1.27 1.27)
			)
			(justify right bottom)
		)
	)
	(label "SPI1.MISO"
		(at 113.03 80.01 0)
		(effects
			(font
				(size 1.27 1.27)
			)
			(justify left bottom)
		)
	)
	(label "DP3.TX3-"
		(at 316.23 39.37 0)
		(effects
			(font
				(size 1.27 1.27)
			)
			(justify left bottom)
		)
	)
	(label "ADDR1"
		(at 328.93 185.42 0)
		(effects
			(font
				(size 1.27 1.27)
			)
			(justify left bottom)
		)
	)
	(label "CAN2.DOUT"
		(at 82.55 62.23 180)
		(effects
			(font
				(size 1.27 1.27)
			)
			(justify right bottom)
		)
	)
	(label "I2S2.CLK"
		(at 128.27 41.91 180)
		(effects
			(font
				(size 1.27 1.27)
			)
			(justify right bottom)
		)
	)
	(label "DP3.TX2+"
		(at 316.23 46.99 0)
		(effects
			(font
				(size 1.27 1.27)
			)
			(justify left bottom)
		)
	)
	(label "PCIe_{C3x2}.~{RST}"
		(at 276.86 52.07 0)
		(effects
			(font
				(size 1.27 1.27)
			)
			(justify left bottom)
		)
	)
	(label "I2S2.FS"
		(at 128.27 44.45 180)
		(effects
			(font
				(size 1.27 1.27)
			)
			(justify right bottom)
		)
	)
	(label "+12V_FMC"
		(at 397.51 196.85 180)
		(effects
			(font
				(size 1.27 1.27)
			)
			(justify right bottom)
		)
	)
	(label "PET0_C2_P"
		(at 198.12 242.57 0)
		(effects
			(font
				(size 1.27 1.27)
			)
			(justify left bottom)
		)
	)
	(label "DP3.TX0+"
		(at 316.23 67.31 0)
		(effects
			(font
				(size 1.27 1.27)
			)
			(justify left bottom)
		)
	)
	(label "PCIe_{C3x2}.RX1-"
		(at 287.02 227.33 180)
		(effects
			(font
				(size 1.27 1.27)
			)
			(justify right bottom)
		)
	)
	(label "I2C_{SYS}.SCL"
		(at 234.95 80.01 0)
		(effects
			(font
				(size 1.27 1.27)
			)
			(justify left bottom)
		)
	)
	(label "DP2.TX3-"
		(at 367.03 72.39 180)
		(effects
			(font
				(size 1.27 1.27)
			)
			(justify right bottom)
		)
	)
	(label "I2S2.SDOUT"
		(at 128.27 49.53 180)
		(effects
			(font
				(size 1.27 1.27)
			)
			(justify right bottom)
		)
	)
	(label "DP1.TX1+"
		(at 250.19 196.85 180)
		(effects
			(font
				(size 1.27 1.27)
			)
			(justify right bottom)
		)
	)
	(label "SPI1.SCK"
		(at 113.03 87.63 0)
		(effects
			(font
				(size 1.27 1.27)
			)
			(justify left bottom)
		)
	)
	(label "PCIe_{C2x1}.TX0-"
		(at 189.23 245.11 180)
		(effects
			(font
				(size 1.27 1.27)
			)
			(justify right bottom)
		)
	)
	(label "PER0_C2_N"
		(at 198.12 224.79 0)
		(effects
			(font
				(size 1.27 1.27)
			)
			(justify left bottom)
		)
	)
	(label "PET0_C3_P"
		(at 251.46 237.49 180)
		(effects
			(font
				(size 1.27 1.27)
			)
			(justify right bottom)
		)
	)
	(label "I2C8.SDA"
		(at 236.22 95.25 0)
		(effects
			(font
				(size 1.27 1.27)
			)
			(justify left bottom)
		)
	)
	(label "I2C0.SCL"
		(at 283.21 102.87 180)
		(effects
			(font
				(size 1.27 1.27)
			)
			(justify right bottom)
		)
	)
	(label "GPIO.18"
		(at 67.31 90.17 0)
		(effects
			(font
				(size 1.27 1.27)
			)
			(justify left bottom)
		)
	)
	(label "PCIe_{C3x2}.RX0-"
		(at 287.02 217.17 180)
		(effects
			(font
				(size 1.27 1.27)
			)
			(justify right bottom)
		)
	)
	(label "PCIe_{C2x1}.TX0+"
		(at 189.23 242.57 180)
		(effects
			(font
				(size 1.27 1.27)
			)
			(justify right bottom)
		)
	)
	(label "UART5.RX"
		(at 245.11 72.39 180)
		(effects
			(font
				(size 1.27 1.27)
			)
			(justify right bottom)
		)
	)
	(label "DP1.TX1-"
		(at 250.19 199.39 180)
		(effects
			(font
				(size 1.27 1.27)
			)
			(justify right bottom)
		)
	)
	(label "+3V3_AUX"
		(at 397.51 246.38 180)
		(effects
			(font
				(size 1.27 1.27)
			)
			(justify right bottom)
		)
	)
	(label "CAN1.DIN"
		(at 82.55 52.07 180)
		(effects
			(font
				(size 1.27 1.27)
			)
			(justify right bottom)
		)
	)
	(label "DP2.TX1+"
		(at 367.03 54.61 180)
		(effects
			(font
				(size 1.27 1.27)
			)
			(justify right bottom)
		)
	)
	(label "+VCC_FMC"
		(at 349.25 228.6 180)
		(effects
			(font
				(size 1.27 1.27)
			)
			(justify right bottom)
		)
	)
	(label "GPIO.27"
		(at 290.83 95.25 180)
		(effects
			(font
				(size 1.27 1.27)
			)
			(justify right bottom)
		)
	)
	(label "+V_{ADJ}"
		(at 181.61 149.86 0)
		(effects
			(font
				(size 1.27 1.27)
			)
			(justify left bottom)
		)
	)
	(label "SPI3.~{CS1}"
		(at 67.31 105.41 0)
		(effects
			(font
				(size 1.27 1.27)
			)
			(justify left bottom)
		)
	)
	(label "I2S3.SDOUT"
		(at 128.27 64.77 180)
		(effects
			(font
				(size 1.27 1.27)
			)
			(justify right bottom)
		)
	)
	(label "+3V3_FMC"
		(at 236.22 118.11 0)
		(effects
			(font
				(size 1.27 1.27)
			)
			(justify left bottom)
		)
	)
	(label "I2C7.SDA"
		(at 236.22 85.09 0)
		(effects
			(font
				(size 1.27 1.27)
			)
			(justify left bottom)
		)
	)
	(label "I2C8.SCL"
		(at 236.22 92.71 0)
		(effects
			(font
				(size 1.27 1.27)
			)
			(justify left bottom)
		)
	)
	(label "PCIe_{C3x2}.RX1+"
		(at 287.02 229.87 180)
		(effects
			(font
				(size 1.27 1.27)
			)
			(justify right bottom)
		)
	)
	(label "DP1.TX2+"
		(at 199.39 181.61 0)
		(effects
			(font
				(size 1.27 1.27)
			)
			(justify left bottom)
		)
	)
	(label "SPI2.MOSI"
		(at 113.03 102.87 0)
		(effects
			(font
				(size 1.27 1.27)
			)
			(justify left bottom)
		)
	)
	(label "PET0_C3_N"
		(at 251.46 240.03 180)
		(effects
			(font
				(size 1.27 1.27)
			)
			(justify right bottom)
		)
	)
	(label "UART5.RTS"
		(at 245.11 62.23 180)
		(effects
			(font
				(size 1.27 1.27)
			)
			(justify right bottom)
		)
	)
	(label "DP1.HPD"
		(at 285.75 72.39 180)
		(effects
			(font
				(size 1.27 1.27)
			)
			(justify right bottom)
		)
	)
	(label "DP1.TX2-"
		(at 199.39 184.15 0)
		(effects
			(font
				(size 1.27 1.27)
			)
			(justify left bottom)
		)
	)
	(label "DP2.TX3+"
		(at 367.03 74.93 180)
		(effects
			(font
				(size 1.27 1.27)
			)
			(justify right bottom)
		)
	)
	(label "DP3.AUX+"
		(at 316.23 77.47 0)
		(effects
			(font
				(size 1.27 1.27)
			)
			(justify left bottom)
		)
	)
	(label "+12V_FMC"
		(at 97.79 242.57 180)
		(effects
			(font
				(size 1.27 1.27)
			)
			(justify right bottom)
		)
	)
	(label "SPI3.~{CS0}"
		(at 113.03 105.41 0)
		(effects
			(font
				(size 1.27 1.27)
			)
			(justify left bottom)
		)
	)
	(label "PCIe_{C2x1}.~{RST}"
		(at 276.86 62.23 0)
		(effects
			(font
				(size 1.27 1.27)
			)
			(justify left bottom)
		)
	)
	(label "UART2.RTS"
		(at 245.11 46.99 180)
		(effects
			(font
				(size 1.27 1.27)
			)
			(justify right bottom)
		)
	)
	(label "+3V3_AUX"
		(at 236.22 107.95 0)
		(effects
			(font
				(size 1.27 1.27)
			)
			(justify left bottom)
		)
	)
	(label "PET1_C3_N"
		(at 251.46 250.19 180)
		(effects
			(font
				(size 1.27 1.27)
			)
			(justify right bottom)
		)
	)
	(label "UART2.RX"
		(at 245.11 57.15 180)
		(effects
			(font
				(size 1.27 1.27)
			)
			(justify right bottom)
		)
	)
	(label "SPI1.~{CS1}"
		(at 113.03 74.93 0)
		(effects
			(font
				(size 1.27 1.27)
			)
			(justify left bottom)
		)
	)
	(label "I2S3.SDIN"
		(at 128.27 67.31 180)
		(effects
			(font
				(size 1.27 1.27)
			)
			(justify right bottom)
		)
	)
	(label "SPI3.MOSI"
		(at 67.31 97.79 0)
		(effects
			(font
				(size 1.27 1.27)
			)
			(justify left bottom)
		)
	)
	(label "CAN1.DOUT"
		(at 82.55 54.61 180)
		(effects
			(font
				(size 1.27 1.27)
			)
			(justify right bottom)
		)
	)
	(label "DP3.AUX-"
		(at 316.23 80.01 0)
		(effects
			(font
				(size 1.27 1.27)
			)
			(justify left bottom)
		)
	)
	(label "PET1_C3_P"
		(at 251.46 247.65 180)
		(effects
			(font
				(size 1.27 1.27)
			)
			(justify right bottom)
		)
	)
	(label "SPI1.~{CS0}"
		(at 113.03 72.39 0)
		(effects
			(font
				(size 1.27 1.27)
			)
			(justify left bottom)
		)
	)
	(label "GPIO.MCLK01"
		(at 116.84 31.75 0)
		(effects
			(font
				(size 1.27 1.27)
			)
			(justify left bottom)
		)
	)
	(label "PCIe_{C2x1}.CLK-"
		(at 175.26 234.95 0)
		(effects
			(font
				(size 1.27 1.27)
			)
			(justify left bottom)
		)
	)
	(label "DP3.TX0-"
		(at 316.23 69.85 0)
		(effects
			(font
				(size 1.27 1.27)
			)
			(justify left bottom)
		)
	)
	(label "+5V_FMC"
		(at 397.51 226.06 180)
		(effects
			(font
				(size 1.27 1.27)
			)
			(justify right bottom)
		)
	)
	(label "+5V_FMC"
		(at 349.25 226.06 180)
		(effects
			(font
				(size 1.27 1.27)
			)
			(justify right bottom)
		)
	)
	(label "ADDR0"
		(at 285.75 113.03 180)
		(effects
			(font
				(size 1.27 1.27)
			)
			(justify right bottom)
		)
	)
	(label "I2C0.SDA"
		(at 326.39 179.07 0)
		(effects
			(font
				(size 1.27 1.27)
			)
			(justify left bottom)
		)
	)
	(label "PCIe_{C3x2}.CLK+"
		(at 287.02 209.55 180)
		(effects
			(font
				(size 1.27 1.27)
			)
			(justify right bottom)
		)
	)
	(label "DP1.TX3-"
		(at 199.39 194.31 0)
		(effects
			(font
				(size 1.27 1.27)
			)
			(justify left bottom)
		)
	)
	(label "SPI2.MISO"
		(at 113.03 97.79 0)
		(effects
			(font
				(size 1.27 1.27)
			)
			(justify left bottom)
		)
	)
	(label "UART2.CTS"
		(at 245.11 49.53 180)
		(effects
			(font
				(size 1.27 1.27)
			)
			(justify right bottom)
		)
	)
	(label "DP3.HPD"
		(at 285.75 82.55 180)
		(effects
			(font
				(size 1.27 1.27)
			)
			(justify right bottom)
		)
	)
	(label "DP1.TX0-"
		(at 250.19 189.23 180)
		(effects
			(font
				(size 1.27 1.27)
			)
			(justify right bottom)
		)
	)
	(label "PET0_C2_N"
		(at 198.12 245.11 0)
		(effects
			(font
				(size 1.27 1.27)
			)
			(justify left bottom)
		)
	)
	(label "PCIe_{C3x2}.~{CLKREQ}"
		(at 276.86 54.61 0)
		(effects
			(font
				(size 1.27 1.27)
			)
			(justify left bottom)
		)
	)
	(label "PCIe_{C2x1}.RX0+"
		(at 175.26 224.79 0)
		(effects
			(font
				(size 1.27 1.27)
			)
			(justify left bottom)
		)
	)
	(label "DP3.TX1-"
		(at 316.23 59.69 0)
		(effects
			(font
				(size 1.27 1.27)
			)
			(justify left bottom)
		)
	)
	(label "+V_{ADJ}"
		(at 152.4 128.27 0)
		(effects
			(font
				(size 1.27 1.27)
			)
			(justify left bottom)
		)
	)
	(label "I2C0.SCL"
		(at 326.39 176.53 0)
		(effects
			(font
				(size 1.27 1.27)
			)
			(justify left bottom)
		)
	)
	(label "SPI2.~{CS0}"
		(at 113.03 90.17 0)
		(effects
			(font
				(size 1.27 1.27)
			)
			(justify left bottom)
		)
	)
	(label "GPIO.USER_LED0"
		(at 67.31 74.93 0)
		(effects
			(font
				(size 1.27 1.27)
			)
			(justify left bottom)
		)
	)
	(label "GPIO.USER_BTN1"
		(at 67.31 85.09 0)
		(effects
			(font
				(size 1.27 1.27)
			)
			(justify left bottom)
		)
	)
	(label "+V_{ADJ}"
		(at 203.2 125.73 180)
		(effects
			(font
				(size 1.27 1.27)
			)
			(justify right bottom)
		)
	)
	(label "GPIO.20"
		(at 67.31 92.71 0)
		(effects
			(font
				(size 1.27 1.27)
			)
			(justify left bottom)
		)
	)
	(label "+3V3_FMC"
		(at 349.25 223.52 180)
		(effects
			(font
				(size 1.27 1.27)
			)
			(justify right bottom)
		)
	)
	(label "PCIe_{C3x2}.RX0+"
		(at 287.02 219.71 180)
		(effects
			(font
				(size 1.27 1.27)
			)
			(justify right bottom)
		)
	)
	(label "PCIe_{C3x2}.TX0+"
		(at 273.05 237.49 0)
		(effects
			(font
				(size 1.27 1.27)
			)
			(justify left bottom)
		)
	)
	(label "PCIe_{C3x2}.CLK-"
		(at 287.02 207.01 180)
		(effects
			(font
				(size 1.27 1.27)
			)
			(justify right bottom)
		)
	)
	(label "ADDR1"
		(at 236.22 115.57 0)
		(effects
			(font
				(size 1.27 1.27)
			)
			(justify left bottom)
		)
	)
	(label "PCIe_{C3x2}.TX0-"
		(at 273.05 240.03 0)
		(effects
			(font
				(size 1.27 1.27)
			)
			(justify left bottom)
		)
	)
	(label "CAN0.DOUT"
		(at 82.55 46.99 180)
		(effects
			(font
				(size 1.27 1.27)
			)
			(justify right bottom)
		)
	)
	(label "+3V3_FMC"
		(at 397.51 236.22 180)
		(effects
			(font
				(size 1.27 1.27)
			)
			(justify right bottom)
		)
	)
	(label "DP1.AUX+"
		(at 250.19 176.53 180)
		(effects
			(font
				(size 1.27 1.27)
			)
			(justify right bottom)
		)
	)
	(label "DP2.TX2+"
		(at 367.03 64.77 180)
		(effects
			(font
				(size 1.27 1.27)
			)
			(justify right bottom)
		)
	)
	(label "PCIe_{C3x2}.TX1+"
		(at 273.05 247.65 0)
		(effects
			(font
				(size 1.27 1.27)
			)
			(justify left bottom)
		)
	)
	(label "GPIO.USER_LED1"
		(at 67.31 77.47 0)
		(effects
			(font
				(size 1.27 1.27)
			)
			(justify left bottom)
		)
	)
	(label "CAN2.DIN"
		(at 82.55 59.69 180)
		(effects
			(font
				(size 1.27 1.27)
			)
			(justify right bottom)
		)
	)
	(label "SPI3.SCK"
		(at 67.31 100.33 0)
		(effects
			(font
				(size 1.27 1.27)
			)
			(justify left bottom)
		)
	)
	(label "DP1.AUX-"
		(at 250.19 179.07 180)
		(effects
			(font
				(size 1.27 1.27)
			)
			(justify right bottom)
		)
	)
	(label "CAN3.DOUT"
		(at 82.55 69.85 180)
		(effects
			(font
				(size 1.27 1.27)
			)
			(justify right bottom)
		)
	)
	(label "I2S3.FS"
		(at 128.27 59.69 180)
		(effects
			(font
				(size 1.27 1.27)
			)
			(justify right bottom)
		)
	)
	(label "GPIO.MCLK03"
		(at 279.4 85.09 0)
		(effects
			(font
				(size 1.27 1.27)
			)
			(justify left bottom)
		)
	)
	(label "GPIO.21"
		(at 290.83 92.71 180)
		(effects
			(font
				(size 1.27 1.27)
			)
			(justify right bottom)
		)
	)
	(label "DP2.AUX+"
		(at 367.03 34.29 180)
		(effects
			(font
				(size 1.27 1.27)
			)
			(justify right bottom)
		)
	)
	(label "DP2.TX1-"
		(at 367.03 52.07 180)
		(effects
			(font
				(size 1.27 1.27)
			)
			(justify right bottom)
		)
	)
	(label "PCIe_{C2x1}.RX0-"
		(at 175.26 222.25 0)
		(effects
			(font
				(size 1.27 1.27)
			)
			(justify left bottom)
		)
	)
	(label "I2C0.SDA"
		(at 283.21 105.41 180)
		(effects
			(font
				(size 1.27 1.27)
			)
			(justify right bottom)
		)
	)
	(label "GPIO.MCLK02"
		(at 116.84 34.29 0)
		(effects
			(font
				(size 1.27 1.27)
			)
			(justify left bottom)
		)
	)
	(label "PER0_C2_P"
		(at 198.12 222.25 0)
		(effects
			(font
				(size 1.27 1.27)
			)
			(justify left bottom)
		)
	)
	(label "GPIO.USER_BTN0"
		(at 67.31 82.55 0)
		(effects
			(font
				(size 1.27 1.27)
			)
			(justify left bottom)
		)
	)
	(label "PCIe_{C2x1}.~{CLKREQ}"
		(at 276.86 64.77 0)
		(effects
			(font
				(size 1.27 1.27)
			)
			(justify left bottom)
		)
	)
	(label "+3V3_FMC"
		(at 285.75 125.73 180)
		(effects
			(font
				(size 1.27 1.27)
			)
			(justify right bottom)
		)
	)
	(label "+12V_FMC"
		(at 285.75 115.57 180)
		(effects
			(font
				(size 1.27 1.27)
			)
			(justify right bottom)
		)
	)
	(label "+V_{ADJ}"
		(at 397.51 205.74 180)
		(effects
			(font
				(size 1.27 1.27)
			)
			(justify right bottom)
		)
	)
	(label "SPI2.SCK"
		(at 113.03 95.25 0)
		(effects
			(font
				(size 1.27 1.27)
			)
			(justify left bottom)
		)
	)
	(label "+3V3_AUX"
		(at 368.3 176.53 180)
		(effects
			(font
				(size 1.27 1.27)
			)
			(justify right bottom)
		)
	)
	(label "UART5.TX"
		(at 245.11 69.85 180)
		(effects
			(font
				(size 1.27 1.27)
			)
			(justify right bottom)
		)
	)
	(label "ADDR0"
		(at 377.19 180.34 0)
		(effects
			(font
				(size 1.27 1.27)
			)
			(justify left bottom)
		)
	)
	(label "ADDR1"
		(at 377.19 185.42 0)
		(effects
			(font
				(size 1.27 1.27)
			)
			(justify left bottom)
		)
	)
	(label "DP1.TX3+"
		(at 199.39 191.77 0)
		(effects
			(font
				(size 1.27 1.27)
			)
			(justify left bottom)
		)
	)
	(label "I2C7.SCL"
		(at 236.22 87.63 0)
		(effects
			(font
				(size 1.27 1.27)
			)
			(justify left bottom)
		)
	)
	(label "UART5.CTS"
		(at 245.11 64.77 180)
		(effects
			(font
				(size 1.27 1.27)
			)
			(justify right bottom)
		)
	)
	(label "DP1.TX0+"
		(at 250.19 186.69 180)
		(effects
			(font
				(size 1.27 1.27)
			)
			(justify right bottom)
		)
	)
	(label "DP2.HPD"
		(at 285.75 74.93 180)
		(effects
			(font
				(size 1.27 1.27)
			)
			(justify right bottom)
		)
	)
	(label "DP2.TX0+"
		(at 367.03 44.45 180)
		(effects
			(font
				(size 1.27 1.27)
			)
			(justify right bottom)
		)
	)
	(label "DP2.TX0-"
		(at 367.03 41.91 180)
		(effects
			(font
				(size 1.27 1.27)
			)
			(justify right bottom)
		)
	)
	(label "+V_{ADJ}"
		(at 71.12 128.27 0)
		(effects
			(font
				(size 1.27 1.27)
			)
			(justify left bottom)
		)
	)
	(label "SPI1.MOSI"
		(at 113.03 82.55 0)
		(effects
			(font
				(size 1.27 1.27)
			)
			(justify left bottom)
		)
	)
	(label "+3V3_FMC"
		(at 199.39 252.73 0)
		(effects
			(font
				(size 1.27 1.27)
			)
			(justify left bottom)
		)
	)
	(label "I2S3.CLK"
		(at 128.27 57.15 180)
		(effects
			(font
				(size 1.27 1.27)
			)
			(justify right bottom)
		)
	)
	(label "+V_{ADJ}"
		(at 121.92 125.73 180)
		(effects
			(font
				(size 1.27 1.27)
			)
			(justify right bottom)
		)
	)
	(label "ADDR0"
		(at 328.93 182.88 0)
		(effects
			(font
				(size 1.27 1.27)
			)
			(justify left bottom)
		)
	)
	(label "I2C_{SYS}.SDA"
		(at 234.95 77.47 0)
		(effects
			(font
				(size 1.27 1.27)
			)
			(justify left bottom)
		)
	)
	(label "UART2.TX"
		(at 245.11 54.61 180)
		(effects
			(font
				(size 1.27 1.27)
			)
			(justify right bottom)
		)
	)
	(label "CAN0.DIN"
		(at 82.55 44.45 180)
		(effects
			(font
				(size 1.27 1.27)
			)
			(justify right bottom)
		)
	)
	(label "I2S2.SDIN"
		(at 128.27 52.07 180)
		(effects
			(font
				(size 1.27 1.27)
			)
			(justify right bottom)
		)
	)
	(label "DP2.TX2-"
		(at 367.03 62.23 180)
		(effects
			(font
				(size 1.27 1.27)
			)
			(justify right bottom)
		)
	)
	(label "DP3.TX2-"
		(at 316.23 49.53 0)
		(effects
			(font
				(size 1.27 1.27)
			)
			(justify left bottom)
		)
	)
	(label "PCIe_{C3x2}.TX1-"
		(at 273.05 250.19 0)
		(effects
			(font
				(size 1.27 1.27)
			)
			(justify left bottom)
		)
	)
	(label "DP3.TX3+"
		(at 316.23 36.83 0)
		(effects
			(font
				(size 1.27 1.27)
			)
			(justify left bottom)
		)
	)
	(label "DP3.TX1+"
		(at 316.23 57.15 0)
		(effects
			(font
				(size 1.27 1.27)
			)
			(justify left bottom)
		)
	)
	(hierarchical_label "I2C0{I2C}"
		(shape bidirectional)
		(at 289.56 100.33 0)
		(effects
			(font
				(size 1.27 1.27)
			)
			(justify left)
		)
	)
	(hierarchical_label "PCIe_{C2x1}{PCIe}"
		(shape bidirectional)
		(at 170.18 219.71 180)
		(effects
			(font
				(size 1.27 1.27)
			)
			(justify right)
		)
	)
	(hierarchical_label "CAN1{CAN}"
		(shape bidirectional)
		(at 66.04 49.53 180)
		(effects
			(font
				(size 1.27 1.27)
			)
			(justify right)
		)
	)
	(hierarchical_label "SPI2{SPI}"
		(shape bidirectional)
		(at 130.81 87.63 0)
		(effects
			(font
				(size 1.27 1.27)
			)
			(justify left)
		)
	)
	(hierarchical_label "DP3{DP}"
		(shape input)
		(at 292.1 80.01 0)
		(effects
			(font
				(size 1.27 1.27)
			)
			(justify left)
		)
	)
	(hierarchical_label "I2C_{SYS}{I2C}"
		(shape bidirectional)
		(at 228.6 74.93 180)
		(effects
			(font
				(size 1.27 1.27)
			)
			(justify right)
		)
	)
	(hierarchical_label "SPI1{SPI}"
		(shape bidirectional)
		(at 130.81 69.85 0)
		(effects
			(font
				(size 1.27 1.27)
			)
			(justify left)
		)
	)
	(hierarchical_label "PCIe_{C3x2}{PCIe}"
		(shape bidirectional)
		(at 292.1 203.2 0)
		(effects
			(font
				(size 1.27 1.27)
			)
			(justify left)
		)
	)
	(hierarchical_label "FMC_PG_M2C"
		(shape bidirectional)
		(at 165.1 29.21 180)
		(effects
			(font
				(size 1.27 1.27)
			)
			(justify right)
		)
	)
	(hierarchical_label "PCIe_{C2x1}{PCIe}"
		(shape bidirectional)
		(at 297.18 59.69 0)
		(effects
			(font
				(size 1.27 1.27)
			)
			(justify left)
		)
	)
	(hierarchical_label "I2S3{I2S}"
		(shape bidirectional)
		(at 134.62 54.61 0)
		(effects
			(font
				(size 1.27 1.27)
			)
			(justify left)
		)
	)
	(hierarchical_label "I2C0{I2C}"
		(shape bidirectional)
		(at 323.85 173.99 180)
		(effects
			(font
				(size 1.27 1.27)
			)
			(justify right)
		)
	)
	(hierarchical_label "CAN0{CAN}"
		(shape bidirectional)
		(at 66.04 41.91 180)
		(effects
			(font
				(size 1.27 1.27)
			)
			(justify right)
		)
	)
	(hierarchical_label "FMC_PRESENT"
		(shape bidirectional)
		(at 204.47 162.56 180)
		(effects
			(font
				(size 1.27 1.27)
			)
			(justify right)
		)
	)
	(hierarchical_label "DP3{DP}"
		(shape input)
		(at 311.15 34.29 180)
		(effects
			(font
				(size 1.27 1.27)
			)
			(justify right)
		)
	)
	(hierarchical_label "UART5{UART}"
		(shape bidirectional)
		(at 228.6 59.69 180)
		(effects
			(font
				(size 1.27 1.27)
			)
			(justify right)
		)
	)
	(hierarchical_label "FMC_PRSNT_M2C_L"
		(shape bidirectional)
		(at 68.58 31.75 180)
		(effects
			(font
				(size 1.27 1.27)
			)
			(justify right)
		)
	)
	(hierarchical_label "UART2{UART}"
		(shape bidirectional)
		(at 228.6 44.45 180)
		(effects
			(font
				(size 1.27 1.27)
			)
			(justify right)
		)
	)
	(hierarchical_label "DP1{DP}"
		(shape input)
		(at 256.54 173.99 0)
		(effects
			(font
				(size 1.27 1.27)
			)
			(justify left)
		)
	)
	(hierarchical_label "I2C8{I2C}"
		(shape bidirectional)
		(at 228.6 90.17 180)
		(effects
			(font
				(size 1.27 1.27)
			)
			(justify right)
		)
	)
	(hierarchical_label "DP1{DP}"
		(shape input)
		(at 193.04 179.07 180)
		(effects
			(font
				(size 1.27 1.27)
			)
			(justify right)
		)
	)
	(hierarchical_label "GPIO{GPIO}"
		(shape bidirectional)
		(at 134.62 29.21 0)
		(effects
			(font
				(size 1.27 1.27)
			)
			(justify left)
		)
	)
	(hierarchical_label "CAN2{CAN}"
		(shape bidirectional)
		(at 66.04 57.15 180)
		(effects
			(font
				(size 1.27 1.27)
			)
			(justify right)
		)
	)
	(hierarchical_label "I2S2{I2S}"
		(shape bidirectional)
		(at 134.62 39.37 0)
		(effects
			(font
				(size 1.27 1.27)
			)
			(justify left)
		)
	)
	(hierarchical_label "DP2{DP}"
		(shape input)
		(at 292.1 72.39 0)
		(effects
			(font
				(size 1.27 1.27)
			)
			(justify left)
		)
	)
	(hierarchical_label "CAN3{CAN}"
		(shape bidirectional)
		(at 66.04 64.77 180)
		(effects
			(font
				(size 1.27 1.27)
			)
			(justify right)
		)
	)
	(hierarchical_label "FMC_PG_C2M"
		(shape bidirectional)
		(at 246.38 29.21 180)
		(effects
			(font
				(size 1.27 1.27)
			)
			(justify right)
		)
	)
	(hierarchical_label "DP2{DP}"
		(shape input)
		(at 373.38 29.21 0)
		(effects
			(font
				(size 1.27 1.27)
			)
			(justify left)
		)
	)
	(hierarchical_label "SPI3{SPI}"
		(shape bidirectional)
		(at 130.81 102.87 0)
		(effects
			(font
				(size 1.27 1.27)
			)
			(justify left)
		)
	)
	(hierarchical_label "I2C7{I2C}"
		(shape bidirectional)
		(at 228.6 82.55 180)
		(effects
			(font
				(size 1.27 1.27)
			)
			(justify right)
		)
	)
	(hierarchical_label "GPIO{GPIO}"
		(shape bidirectional)
		(at 297.18 82.55 0)
		(effects
			(font
				(size 1.27 1.27)
			)
			(justify left)
		)
	)
	(hierarchical_label "SPI3{SPI}"
		(shape bidirectional)
		(at 62.23 95.25 180)
		(effects
			(font
				(size 1.27 1.27)
			)
			(justify right)
		)
	)
	(hierarchical_label "PCIe_{C3x2}{PCIe}"
		(shape bidirectional)
		(at 297.18 49.53 0)
		(effects
			(font
				(size 1.27 1.27)
			)
			(justify left)
		)
	)
	(hierarchical_label "DP1{DP}"
		(shape input)
		(at 292.1 69.85 0)
		(effects
			(font
				(size 1.27 1.27)
			)
			(justify left)
		)
	)
	(hierarchical_label "GPIO{GPIO}"
		(shape bidirectional)
		(at 60.96 71.12 180)
		(effects
			(font
				(size 1.27 1.27)
			)
			(justify right)
		)
	)
	(rule_area
		(polyline
			(pts
				(xy 251.46 255.27) (xy 288.29 255.27) (xy 288.29 203.2) (xy 251.46 203.2)
			)
			(stroke
				(width 0)
				(type dash)
			)
			(fill
				(type none)
			)
		)
	)
	(rule_area
		(polyline
			(pts
				(xy 173.99 247.65) (xy 210.82 247.65) (xy 210.82 215.9) (xy 173.99 215.9)
			)
			(stroke
				(width 0)
				(type dash)
			)
			(fill
				(type none)
			)
		)
	)
	(netclass_flag ""
		(length 2.54)
		(shape round)
		(at 370.84 29.21 0)
		(effects
			(font
				(size 1.27 1.27)
			)
			(justify left bottom)
		)
		(property "Netclass" "85Ohm-diff_DP"
			(at 371.094 24.638 0)
			(effects
				(font
					(size 1.27 1.27)
				)
				(justify right)
			)
		)
		(property "Component Class" ""
			(at 533.4 -12.7 0)
			(effects
				(font
					(size 1.27 1.27)
					(italic yes)
				)
				(justify left)
			)
		)
	)
	(netclass_flag ""
		(length 2.54)
		(shape round)
		(at 312.42 34.29 0)
		(effects
			(font
				(size 1.27 1.27)
			)
			(justify left bottom)
		)
		(property "Netclass" "85Ohm-diff_DP"
			(at 313.182 29.464 0)
			(effects
				(font
					(size 1.27 1.27)
				)
				(justify right)
			)
		)
		(property "Component Class" ""
			(at 474.98 -7.62 0)
			(effects
				(font
					(size 1.27 1.27)
					(italic yes)
				)
				(justify left)
			)
		)
	)
	(netclass_flag ""
		(length 2.54)
		(shape round)
		(at 288.29 255.27 180)
		(fields_autoplaced yes)
		(effects
			(font
				(size 1.27 1.27)
			)
			(justify right bottom)
		)
		(property "Netclass" "85Ohm-diff_PCIE"
			(at 287.5915 257.81 0)
			(effects
				(font
					(size 1.27 1.27)
				)
				(justify right)
			)
		)
		(property "Component Class" ""
			(at 450.85 297.18 0)
			(effects
				(font
					(size 1.27 1.27)
					(italic yes)
				)
			)
		)
	)
	(netclass_flag ""
		(length 2.54)
		(shape round)
		(at 254 173.99 0)
		(effects
			(font
				(size 1.27 1.27)
			)
			(justify left bottom)
		)
		(property "Netclass" "85Ohm-diff_DP"
			(at 253.746 169.418 0)
			(effects
				(font
					(size 1.27 1.27)
				)
				(justify left)
			)
		)
		(property "Component Class" ""
			(at 91.44 132.08 0)
			(effects
				(font
					(size 1.27 1.27)
					(italic yes)
				)
				(justify right)
			)
		)
	)
	(netclass_flag ""
		(length 2.54)
		(shape round)
		(at 187.96 247.65 180)
		(fields_autoplaced yes)
		(effects
			(font
				(size 1.27 1.27)
			)
			(justify right bottom)
		)
		(property "Netclass" "85Ohm-diff_PCIE"
			(at 187.2615 250.19 0)
			(effects
				(font
					(size 1.27 1.27)
				)
				(justify right)
			)
		)
		(property "Component Class" ""
			(at 350.52 289.56 0)
			(effects
				(font
					(size 1.27 1.27)
					(italic yes)
				)
			)
		)
	)
	(symbol
		(lib_id "antmicropower:VCC")
		(at 379.73 195.58 0)
		(mirror y)
		(unit 1)
		(exclude_from_sim no)
		(in_bom yes)
		(on_board yes)
		(dnp no)
		(property "Reference" "#PWR0107"
			(at 379.73 199.39 0)
			(effects
				(font
					(size 1.27 1.27)
				)
				(hide yes)
			)
		)
		(property "Value" "+12V"
			(at 376.682 191.516 0)
			(effects
				(font
					(size 1.27 1.27)
				)
				(justify right)
			)
		)
		(property "Footprint" ""
			(at 379.73 195.58 0)
			(effects
				(font
					(size 1.27 1.27)
				)
				(hide yes)
			)
		)
		(property "Datasheet" ""
			(at 379.73 195.58 0)
			(effects
				(font
					(size 1.27 1.27)
				)
				(hide yes)
			)
		)
		(property "Description" ""
			(at 379.73 195.58 0)
			(effects
				(font
					(size 1.27 1.27)
				)
				(hide yes)
			)
		)
		(pin "1"
		)
		(instances
			(project "jetson-agx-thor-baseboard"
				(path ""
					(reference "#PWR0107")
					(unit 1)
				)
			)
		)
	)
	(symbol
		(lib_id "antmicropower:GND")
		(at 273.05 129.54 0)
		(unit 1)
		(exclude_from_sim no)
		(in_bom yes)
		(on_board yes)
		(dnp no)
		(fields_autoplaced yes)
		(property "Reference" "#PWR0435"
			(at 281.94 132.08 0)
			(effects
				(font
					(size 1.27 1.27)
					(thickness 0.15)
				)
				(justify left bottom)
				(hide yes)
			)
		)
		(property "Value" "GND"
			(at 273.05 134.62 0)
			(effects
				(font
					(size 1.27 1.27)
					(thickness 0.15)
				)
			)
		)
		(property "Footprint" ""
			(at 281.94 137.16 0)
			(effects
				(font
					(size 1.27 1.27)
					(thickness 0.15)
				)
				(justify left bottom)
				(hide yes)
			)
		)
		(property "Datasheet" ""
			(at 281.94 142.24 0)
			(effects
				(font
					(size 1.27 1.27)
					(thickness 0.15)
				)
				(justify left bottom)
				(hide yes)
			)
		)
		(property "Description" ""
			(at 273.05 129.54 0)
			(effects
				(font
					(size 1.27 1.27)
				)
				(hide yes)
			)
		)
		(property "Author" "Antmicro"
			(at 281.94 137.16 0)
			(effects
				(font
					(size 1.27 1.27)
					(thickness 0.15)
				)
				(justify left bottom)
				(hide yes)
			)
		)
		(property "License" "Apache-2.0"
			(at 281.94 139.7 0)
			(effects
				(font
					(size 1.27 1.27)
					(thickness 0.15)
				)
				(justify left bottom)
				(hide yes)
			)
		)
		(pin "1"
		)
		(instances
			(project "jetson-agx-thor-baseboard"
				(path ""
					(reference "#PWR0435")
					(unit 1)
				)
			)
		)
	)
	(symbol
		(lib_id "antmicroTestPoints:TP_0.75mm_SMD")
		(at 83.82 234.95 0)
		(unit 1)
		(exclude_from_sim no)
		(in_bom no)
		(on_board yes)
		(dnp no)
		(property "Reference" "TP115"
			(at 88.138 234.95 0)
			(effects
				(font
					(size 1.27 1.27)
					(thickness 0.15)
				)
				(justify left)
			)
		)
		(property "Value" "TP_0.75mm_SMD"
			(at 93.98 238.76 0)
			(effects
				(font
					(size 1.27 1.27)
					(thickness 0.15)
				)
				(justify left bottom)
				(hide yes)
			)
		)
		(property "Footprint" "antmicro-footprints:TP_SMD_0.75mm"
			(at 93.98 241.3 0)
			(effects
				(font
					(size 1.27 1.27)
					(thickness 0.15)
				)
				(justify left bottom)
				(hide yes)
			)
		)
		(property "Datasheet" ""
			(at 101.6 247.65 0)
			(effects
				(font
					(size 1.27 1.27)
					(thickness 0.15)
				)
				(justify left bottom)
				(hide yes)
			)
		)
		(property "Description" "SMT test point"
			(at 94.615 248.92 0)
			(effects
				(font
					(size 1.27 1.27)
				)
				(justify left bottom)
				(hide yes)
			)
		)
		(property "MPN" ""
			(at 94.615 246.38 0)
			(effects
				(font
					(size 1.27 1.27)
					(thickness 0.15)
				)
				(justify left bottom)
				(hide yes)
			)
		)
		(property "Manufacturer" ""
			(at 94.615 241.3 0)
			(effects
				(font
					(size 1.27 1.27)
					(thickness 0.15)
				)
				(justify left bottom)
				(hide yes)
			)
		)
		(property "Author" "Antmicro"
			(at 93.98 243.84 0)
			(effects
				(font
					(size 1.27 1.27)
					(thickness 0.15)
				)
				(justify left bottom)
				(hide yes)
			)
		)
		(property "License" "Apache-2.0"
			(at 93.98 246.38 0)
			(effects
				(font
					(size 1.27 1.27)
					(thickness 0.15)
				)
				(justify left bottom)
				(hide yes)
			)
		)
		(pin "1"
		)
		(instances
			(project "jetson-agx-thor-baseboard"
				(path ""
					(reference "TP115")
					(unit 1)
				)
			)
		)
	)
	(symbol
		(lib_id "antmicropower:PWR_FLAG")
		(at 358.14 175.26 0)
		(unit 1)
		(exclude_from_sim no)
		(in_bom yes)
		(on_board yes)
		(dnp no)
		(fields_autoplaced yes)
		(property "Reference" "#FLG015"
			(at 358.14 173.355 0)
			(effects
				(font
					(size 1.27 1.27)
				)
				(hide yes)
			)
		)
		(property "Value" "PWR_FLAG"
			(at 358.14 170.18 0)
			(effects
				(font
					(size 1.27 1.27)
				)
			)
		)
		(property "Footprint" ""
			(at 358.14 175.26 0)
			(effects
				(font
					(size 1.27 1.27)
				)
				(hide yes)
			)
		)
		(property "Datasheet" ""
			(at 358.14 175.26 0)
			(effects
				(font
					(size 1.27 1.27)
				)
				(hide yes)
			)
		)
		(property "Description" ""
			(at 358.14 177.8 0)
			(effects
				(font
					(size 1.27 1.27)
				)
				(justify left bottom)
				(hide yes)
			)
		)
		(pin "1"
		)
		(instances
			(project ""
				(path ""
					(reference "#FLG015")
					(unit 1)
				)
			)
		)
	)
	(symbol
		(lib_id "antmicropower:GND")
		(at 358.14 236.22 0)
		(unit 1)
		(exclude_from_sim no)
		(in_bom yes)
		(on_board yes)
		(dnp no)
		(property "Reference" "#PWR0442"
			(at 367.03 238.76 0)
			(effects
				(font
					(size 1.27 1.27)
					(thickness 0.15)
				)
				(justify left bottom)
				(hide yes)
			)
		)
		(property "Value" "GND"
			(at 358.14 240.03 0)
			(effects
				(font
					(size 1.27 1.27)
					(thickness 0.15)
				)
			)
		)
		(property "Footprint" ""
			(at 367.03 243.84 0)
			(effects
				(font
					(size 1.27 1.27)
					(thickness 0.15)
				)
				(justify left bottom)
				(hide yes)
			)
		)
		(property "Datasheet" ""
			(at 367.03 248.92 0)
			(effects
				(font
					(size 1.27 1.27)
					(thickness 0.15)
				)
				(justify left bottom)
				(hide yes)
			)
		)
		(property "Description" ""
			(at 358.14 236.22 0)
			(effects
				(font
					(size 1.27 1.27)
				)
				(hide yes)
			)
		)
		(property "Author" "Antmicro"
			(at 367.03 243.84 0)
			(effects
				(font
					(size 1.27 1.27)
					(thickness 0.15)
				)
				(justify left bottom)
				(hide yes)
			)
		)
		(property "License" "Apache-2.0"
			(at 367.03 246.38 0)
			(effects
				(font
					(size 1.27 1.27)
					(thickness 0.15)
				)
				(justify left bottom)
				(hide yes)
			)
		)
		(pin "1"
		)
		(instances
			(project "jetson-agx-thor-baseboard"
				(path ""
					(reference "#PWR0442")
					(unit 1)
				)
			)
		)
	)
	(symbol
		(lib_id "antmicroB2BConnectors:ASP-208571-01_mounting_holes")
		(at 81.28 153.67 0)
		(mirror y)
		(unit 7)
		(exclude_from_sim no)
		(in_bom yes)
		(on_board yes)
		(dnp no)
		(fields_autoplaced yes)
		(property "Reference" "J18"
			(at 69.85 146.05 0)
			(effects
				(font
					(size 1.27 1.27)
					(thickness 0.15)
				)
			)
		)
		(property "Value" "ASP-208571-01_mounting_holes"
			(at 44.45 163.83 0)
			(effects
				(font
					(size 1.27 1.27)
					(thickness 0.15)
				)
				(justify left bottom)
				(hide yes)
			)
		)
		(property "Footprint" "antmicro-footprints:ASP-208571-01_mounting_holes"
			(at 44.45 166.37 0)
			(effects
				(font
					(size 1.27 1.27)
					(thickness 0.15)
				)
				(justify left bottom)
				(hide yes)
			)
		)
		(property "Datasheet" "https://suddendocs.samtec.com/prints/asp-208571-01-mkt.pdf"
			(at 44.45 168.91 0)
			(effects
				(font
					(size 1.27 1.27)
					(thickness 0.15)
				)
				(justify left bottom)
				(hide yes)
			)
		)
		(property "Description" "FMC connector"
			(at 44.45 179.07 0)
			(effects
				(font
					(size 1.27 1.27)
				)
				(justify left bottom)
				(hide yes)
			)
		)
		(property "MPN" "ASP-208571-01"
			(at 69.85 148.59 0)
			(effects
				(font
					(size 1.27 1.27)
					(thickness 0.15)
				)
			)
		)
		(property "Manufacturer" "Samtec"
			(at 44.45 171.45 0)
			(effects
				(font
					(size 1.27 1.27)
					(thickness 0.15)
				)
				(justify left bottom)
				(hide yes)
			)
		)
		(property "Author" "Antmicro"
			(at 44.45 173.99 0)
			(effects
				(font
					(size 1.27 1.27)
					(thickness 0.15)
				)
				(justify left bottom)
				(hide yes)
			)
		)
		(property "License" "Apache-2.0"
			(at 44.45 176.53 0)
			(effects
				(font
					(size 1.27 1.27)
					(thickness 0.15)
				)
				(justify left bottom)
				(hide yes)
			)
		)
		(pin "A40"
		)
		(pin "Z01"
		)
		(pin "A09"
		)
		(pin "Y28"
		)
		(pin "D27"
		)
		(pin "B33"
		)
		(pin "C25"
		)
		(pin "C20"
		)
		(pin "Z05"
		)
		(pin "A10"
		)
		(pin "B14"
		)
		(pin "Y39"
		)
		(pin "C36"
		)
		(pin "F14"
		)
		(pin "H02"
		)
		(pin "H03"
		)
		(pin "A28"
		)
		(pin "C37"
		)
		(pin "A26"
		)
		(pin "C19"
		)
		(pin "Z06"
		)
		(pin "C28"
		)
		(pin "B10"
		)
		(pin "Z27"
		)
		(pin "B40"
		)
		(pin "Z28"
		)
		(pin "Z26"
		)
		(pin "C24"
		)
		(pin "B09"
		)
		(pin "Y27"
		)
		(pin "C08"
		)
		(pin "Z04"
		)
		(pin "A36"
		)
		(pin "C02"
		)
		(pin "A19"
		)
		(pin "E34"
		)
		(pin "K28"
		)
		(pin "K29"
		)
		(pin "G20"
		)
		(pin "G21"
		)
		(pin "A08"
		)
		(pin "B27"
		)
		(pin "D22"
		)
		(pin "F25"
		)
		(pin "C30"
		)
		(pin "D04"
		)
		(pin "A30"
		)
		(pin "A38"
		)
		(pin "B37"
		)
		(pin "G26"
		)
		(pin "G27"
		)
		(pin "C03"
		)
		(pin "F07"
		)
		(pin "D34"
		)
		(pin "G08"
		)
		(pin "G18"
		)
		(pin "G19"
		)
		(pin "G01"
		)
		(pin "A20"
		)
		(pin "M04"
		)
		(pin "M05"
		)
		(pin "Y08"
		)
		(pin "F39"
		)
		(pin "F19"
		)
		(pin "K04"
		)
		(pin "K05"
		)
		(pin "G12"
		)
		(pin "G13"
		)
		(pin "Y02"
		)
		(pin "J32"
		)
		(pin "J33"
		)
		(pin "B11"
		)
		(pin "D07"
		)
		(pin "C33"
		)
		(pin "A17"
		)
		(pin "D14"
		)
		(pin "A15"
		)
		(pin "B39"
		)
		(pin "A18"
		)
		(pin "B21"
		)
		(pin "D11"
		)
		(pin "Y15"
		)
		(pin "B16"
		)
		(pin "Y09"
		)
		(pin "F29"
		)
		(pin "J30"
		)
		(pin "J31"
		)
		(pin "B19"
		)
		(pin "A05"
		)
		(pin "B38"
		)
		(pin "E22"
		)
		(pin "D15"
		)
		(pin "L02"
		)
		(pin "L03"
		)
		(pin "Y37"
		)
		(pin "E07"
		)
		(pin "A22"
		)
		(pin "H20"
		)
		(pin "H21"
		)
		(pin "Z39"
		)
		(pin "F37"
		)
		(pin "B30"
		)
		(pin "Z15"
		)
		(pin "H36"
		)
		(pin "H37"
		)
		(pin "D16"
		)
		(pin "D37"
		)
		(pin "C40"
		)
		(pin "E29"
		)
		(pin "Y36"
		)
		(pin "K10"
		)
		(pin "K11"
		)
		(pin "F38"
		)
		(pin "B04"
		)
		(pin "F15"
		)
		(pin "J28"
		)
		(pin "J29"
		)
		(pin "B17"
		)
		(pin "E37"
		)
		(pin "E09"
		)
		(pin "Z23"
		)
		(pin "J06"
		)
		(pin "J07"
		)
		(pin "Z30"
		)
		(pin "C31"
		)
		(pin "Z37"
		)
		(pin "Z33"
		)
		(pin "Z29"
		)
		(pin "Y26"
		)
		(pin "H06"
		)
		(pin "H07"
		)
		(pin "C10"
		)
		(pin "F27"
		)
		(pin "A03"
		)
		(pin "M10"
		)
		(pin "M11"
		)
		(pin "M12"
		)
		(pin "L04"
		)
		(pin "L05"
		)
		(pin "A24"
		)
		(pin "M28"
		)
		(pin "M29"
		)
		(pin "M30"
		)
		(pin "D32"
		)
		(pin "H18"
		)
		(pin "H19"
		)
		(pin "F03"
		)
		(pin "L08"
		)
		(pin "L09"
		)
		(pin "A01"
		)
		(pin "B32"
		)
		(pin "K36"
		)
		(pin "K37"
		)
		(pin "C01"
		)
		(pin "D18"
		)
		(pin "E12"
		)
		(pin "K16"
		)
		(pin "K17"
		)
		(pin "Y11"
		)
		(pin "B31"
		)
		(pin "D28"
		)
		(pin "D23"
		)
		(pin "Z18"
		)
		(pin "D17"
		)
		(pin "F32"
		)
		(pin "B20"
		)
		(pin "C18"
		)
		(pin "A25"
		)
		(pin "Y05"
		)
		(pin "J26"
		)
		(pin "J27"
		)
		(pin "Y33"
		)
		(pin "A37"
		)
		(pin "Z21"
		)
		(pin "D09"
		)
		(pin "B26"
		)
		(pin "A35"
		)
		(pin "D20"
		)
		(pin "A11"
		)
		(pin "C15"
		)
		(pin "G14"
		)
		(pin "G15"
		)
		(pin "D01"
		)
		(pin "D21"
		)
		(pin "M34"
		)
		(pin "M35"
		)
		(pin "M36"
		)
		(pin "L32"
		)
		(pin "L33"
		)
		(pin "D31"
		)
		(pin "Z07"
		)
		(pin "M31"
		)
		(pin "M32"
		)
		(pin "M33"
		)
		(pin "K18"
		)
		(pin "K19"
		)
		(pin "F06"
		)
		(pin "Z16"
		)
		(pin "H32"
		)
		(pin "H33"
		)
		(pin "Z36"
		)
		(pin "F05"
		)
		(pin "F02"
		)
		(pin "E05"
		)
		(pin "F40"
		)
		(pin "E39"
		)
		(pin "H08"
		)
		(pin "H09"
		)
		(pin "B02"
		)
		(pin "E16"
		)
		(pin "E38"
		)
		(pin "Z12"
		)
		(pin "A34"
		)
		(pin "K08"
		)
		(pin "K09"
		)
		(pin "E31"
		)
		(pin "Y06"
		)
		(pin "F11"
		)
		(pin "F08"
		)
		(pin "A32"
		)
		(pin "Y22"
		)
		(pin "H12"
		)
		(pin "H13"
		)
		(pin "A27"
		)
		(pin "C05"
		)
		(pin "K12"
		)
		(pin "K13"
		)
		(pin "L14"
		)
		(pin "L15"
		)
		(pin "E25"
		)
		(pin "L18"
		)
		(pin "L19"
		)
		(pin "M19"
		)
		(pin "M20"
		)
		(pin "M21"
		)
		(pin "J14"
		)
		(pin "J15"
		)
		(pin "G40"
		)
		(pin "H01"
		)
		(pin "Y25"
		)
		(pin "A33"
		)
		(pin "Z35"
		)
		(pin "H38"
		)
		(pin "H39"
		)
		(pin "D29"
		)
		(pin "E02"
		)
		(pin "D10"
		)
		(pin "C12"
		)
		(pin "C26"
		)
		(pin "M40"
		)
		(pin "B24"
		)
		(pin "Y24"
		)
		(pin "F33"
		)
		(pin "F21"
		)
		(pin "E20"
		)
		(pin "D06"
		)
		(pin "C29"
		)
		(pin "E23"
		)
		(pin "J04"
		)
		(pin "J05"
		)
		(pin "B28"
		)
		(pin "K30"
		)
		(pin "K31"
		)
		(pin "B08"
		)
		(pin "L12"
		)
		(pin "L13"
		)
		(pin "J38"
		)
		(pin "J39"
		)
		(pin "D24"
		)
		(pin "E06"
		)
		(pin "D35"
		)
		(pin "G07"
		)
		(pin "C39"
		)
		(pin "E04"
		)
		(pin "L34"
		)
		(pin "L35"
		)
		(pin "D02"
		)
		(pin "Z22"
		)
		(pin "K14"
		)
		(pin "K15"
		)
		(pin "Y34"
		)
		(pin "M08"
		)
		(pin "M09"
		)
		(pin "D30"
		)
		(pin "G10"
		)
		(pin "G11"
		)
		(pin "C11"
		)
		(pin "E33"
		)
		(pin "G38"
		)
		(pin "G39"
		)
		(pin "F34"
		)
		(pin "H04"
		)
		(pin "H05"
		)
		(pin "F09"
		)
		(pin "G22"
		)
		(pin "G23"
		)
		(pin "B34"
		)
		(pin "Z20"
		)
		(pin "Y03"
		)
		(pin "M06"
		)
		(pin "M07"
		)
		(pin "K38"
		)
		(pin "K39"
		)
		(pin "Y21"
		)
		(pin "K24"
		)
		(pin "K25"
		)
		(pin "E21"
		)
		(pin "L20"
		)
		(pin "L21"
		)
		(pin "E11"
		)
		(pin "K22"
		)
		(pin "K23"
		)
		(pin "B12"
		)
		(pin "J22"
		)
		(pin "J23"
		)
		(pin "A07"
		)
		(pin "E32"
		)
		(pin "L36"
		)
		(pin "L37"
		)
		(pin "L24"
		)
		(pin "L25"
		)
		(pin "Y32"
		)
		(pin "F13"
		)
		(pin "G09"
		)
		(pin "Y01"
		)
		(pin "K06"
		)
		(pin "K07"
		)
		(pin "G28"
		)
		(pin "G29"
		)
		(pin "K40"
		)
		(pin "L01"
		)
		(pin "J02"
		)
		(pin "J03"
		)
		(pin "J12"
		)
		(pin "J13"
		)
		(pin "M25"
		)
		(pin "M26"
		)
		(pin "M27"
		)
		(pin "A13"
		)
		(pin "F20"
		)
		(pin "M37"
		)
		(pin "M38"
		)
		(pin "M39"
		)
		(pin "Y10"
		)
		(pin "G32"
		)
		(pin "G33"
		)
		(pin "A29"
		)
		(pin "L10"
		)
		(pin "L11"
		)
		(pin "G24"
		)
		(pin "G25"
		)
		(pin "E08"
		)
		(pin "C06"
		)
		(pin "A12"
		)
		(pin "F12"
		)
		(pin "C16"
		)
		(pin "Z09"
		)
		(pin "E19"
		)
		(pin "D03"
		)
		(pin "E24"
		)
		(pin "F23"
		)
		(pin "G16"
		)
		(pin "G17"
		)
		(pin "A23"
		)
		(pin "D12"
		)
		(pin "C07"
		)
		(pin "L30"
		)
		(pin "L31"
		)
		(pin "B29"
		)
		(pin "B15"
		)
		(pin "J16"
		)
		(pin "J17"
		)
		(pin "K26"
		)
		(pin "K27"
		)
		(pin "A16"
		)
		(pin "E01"
		)
		(pin "Y12"
		)
		(pin "G04"
		)
		(pin "C32"
		)
		(pin "B22"
		)
		(pin "Y16"
		)
		(pin "G34"
		)
		(pin "G35"
		)
		(pin "A02"
		)
		(pin "D40"
		)
		(pin "Y38"
		)
		(pin "D08"
		)
		(pin "C27"
		)
		(pin "J36"
		)
		(pin "J37"
		)
		(pin "K34"
		)
		(pin "K35"
		)
		(pin "M02"
		)
		(pin "M03"
		)
		(pin "B01"
		)
		(pin "E35"
		)
		(pin "Y13"
		)
		(pin "L26"
		)
		(pin "L27"
		)
		(pin "G36"
		)
		(pin "G37"
		)
		(pin "K32"
		)
		(pin "K33"
		)
		(pin "Y14"
		)
		(pin "D13"
		)
		(pin "D25"
		)
		(pin "F10"
		)
		(pin "E10"
		)
		(pin "E26"
		)
		(pin "E18"
		)
		(pin "F24"
		)
		(pin "Z10"
		)
		(pin "H40"
		)
		(pin "J01"
		)
		(pin "G05"
		)
		(pin "Z17"
		)
		(pin "F22"
		)
		(pin "A14"
		)
		(pin "E30"
		)
		(pin "Z13"
		)
		(pin "H22"
		)
		(pin "H23"
		)
		(pin "E28"
		)
		(pin "F36"
		)
		(pin "B18"
		)
		(pin "Z08"
		)
		(pin "H34"
		)
		(pin "H35"
		)
		(pin "J08"
		)
		(pin "J09"
		)
		(pin "C23"
		)
		(pin "J40"
		)
		(pin "K01"
		)
		(pin "Y07"
		)
		(pin "H14"
		)
		(pin "H15"
		)
		(pin "D36"
		)
		(pin "Y35"
		)
		(pin "C13"
		)
		(pin "F30"
		)
		(pin "L40"
		)
		(pin "M01"
		)
		(pin "F17"
		)
		(pin "Z03"
		)
		(pin "F28"
		)
		(pin "Z40"
		)
		(pin "A39"
		)
		(pin "Y40"
		)
		(pin "M13"
		)
		(pin "M14"
		)
		(pin "M15"
		)
		(pin "D38"
		)
		(pin "Y29"
		)
		(pin "F18"
		)
		(pin "E40"
		)
		(pin "B36"
		)
		(pin "E15"
		)
		(pin "C09"
		)
		(pin "E27"
		)
		(pin "Z31"
		)
		(pin "A06"
		)
		(pin "L22"
		)
		(pin "L23"
		)
		(pin "C34"
		)
		(pin "Y19"
		)
		(pin "J18"
		)
		(pin "J19"
		)
		(pin "L38"
		)
		(pin "L39"
		)
		(pin "G03"
		)
		(pin "F01"
		)
		(pin "M16"
		)
		(pin "M17"
		)
		(pin "M18"
		)
		(pin "J20"
		)
		(pin "J21"
		)
		(pin "H26"
		)
		(pin "H27"
		)
		(pin "Y20"
		)
		(pin "H28"
		)
		(pin "H29"
		)
		(pin "Z34"
		)
		(pin "D26"
		)
		(pin "Y31"
		)
		(pin "G06"
		)
		(pin "Z11"
		)
		(pin "H30"
		)
		(pin "H31"
		)
		(pin "Y04"
		)
		(pin "Z24"
		)
		(pin "D33"
		)
		(pin "F35"
		)
		(pin "B35"
		)
		(pin "B06"
		)
		(pin "B23"
		)
		(pin "M22"
		)
		(pin "M23"
		)
		(pin "M24"
		)
		(pin "Y30"
		)
		(pin "B07"
		)
		(pin "C21"
		)
		(pin "H16"
		)
		(pin "H17"
		)
		(pin "H24"
		)
		(pin "H25"
		)
		(pin "C04"
		)
		(pin "A31"
		)
		(pin "A04"
		)
		(pin "E14"
		)
		(pin "Z38"
		)
		(pin "E17"
		)
		(pin "A21"
		)
		(pin "B03"
		)
		(pin "F04"
		)
		(pin "B13"
		)
		(pin "C14"
		)
		(pin "Z19"
		)
		(pin "Y18"
		)
		(pin "Z14"
		)
		(pin "Z25"
		)
		(pin "J24"
		)
		(pin "J25"
		)
		(pin "H10"
		)
		(pin "H11"
		)
		(pin "K20"
		)
		(pin "K21"
		)
		(pin "F31"
		)
		(pin "F16"
		)
		(pin "E13"
		)
		(pin "F26"
		)
		(pin "C22"
		)
		(pin "E36"
		)
		(pin "J34"
		)
		(pin "J35"
		)
		(pin "C35"
		)
		(pin "L16"
		)
		(pin "L17"
		)
		(pin "J10"
		)
		(pin "J11"
		)
		(pin "L06"
		)
		(pin "L07"
		)
		(pin "D19"
		)
		(pin "Z02"
		)
		(pin "D39"
		)
		(pin "Z32"
		)
		(pin "B25"
		)
		(pin "B05"
		)
		(pin "G30"
		)
		(pin "G31"
		)
		(pin "K02"
		)
		(pin "K03"
		)
		(pin "E03"
		)
		(pin "C38"
		)
		(pin "C17"
		)
		(pin "G02"
		)
		(pin "Y23"
		)
		(pin "D05"
		)
		(pin "L28"
		)
		(pin "L29"
		)
		(pin "Y17"
		)
		(instances
			(project "jetson-agx-thor-baseboard"
				(path ""
					(reference "J18")
					(unit 7)
				)
			)
		)
	)
	(symbol
		(lib_id "antmicroTestPoints:TP_0.75mm_SMD")
		(at 118.11 252.73 0)
		(mirror y)
		(unit 1)
		(exclude_from_sim no)
		(in_bom no)
		(on_board yes)
		(dnp no)
		(property "Reference" "TP111"
			(at 113.792 252.73 0)
			(effects
				(font
					(size 1.27 1.27)
					(thickness 0.15)
				)
				(justify left)
			)
		)
		(property "Value" "TP_0.75mm_SMD"
			(at 107.95 256.54 0)
			(effects
				(font
					(size 1.27 1.27)
					(thickness 0.15)
				)
				(justify left bottom)
				(hide yes)
			)
		)
		(property "Footprint" "antmicro-footprints:TP_SMD_0.75mm"
			(at 107.95 259.08 0)
			(effects
				(font
					(size 1.27 1.27)
					(thickness 0.15)
				)
				(justify left bottom)
				(hide yes)
			)
		)
		(property "Datasheet" ""
			(at 100.33 265.43 0)
			(effects
				(font
					(size 1.27 1.27)
					(thickness 0.15)
				)
				(justify left bottom)
				(hide yes)
			)
		)
		(property "Description" "SMT test point"
			(at 107.315 266.7 0)
			(effects
				(font
					(size 1.27 1.27)
				)
				(justify left bottom)
				(hide yes)
			)
		)
		(property "MPN" ""
			(at 107.315 264.16 0)
			(effects
				(font
					(size 1.27 1.27)
					(thickness 0.15)
				)
				(justify left bottom)
				(hide yes)
			)
		)
		(property "Manufacturer" ""
			(at 107.315 259.08 0)
			(effects
				(font
					(size 1.27 1.27)
					(thickness 0.15)
				)
				(justify left bottom)
				(hide yes)
			)
		)
		(property "Author" "Antmicro"
			(at 107.95 261.62 0)
			(effects
				(font
					(size 1.27 1.27)
					(thickness 0.15)
				)
				(justify left bottom)
				(hide yes)
			)
		)
		(property "License" "Apache-2.0"
			(at 107.95 264.16 0)
			(effects
				(font
					(size 1.27 1.27)
					(thickness 0.15)
				)
				(justify left bottom)
				(hide yes)
			)
		)
		(pin "1"
		)
		(instances
			(project "jetson-agx-thor-baseboard"
				(path ""
					(reference "TP111")
					(unit 1)
				)
			)
		)
	)
	(symbol
		(lib_id "antmicroCapacitorsmisc:C_22u_25V_0805")
		(at 367.03 234.95 90)
		(unit 1)
		(exclude_from_sim no)
		(in_bom yes)
		(on_board yes)
		(dnp no)
		(property "Reference" "C229"
			(at 364.49 229.8636 90)
			(effects
				(font
					(size 1.27 1.27)
					(thickness 0.15)
				)
				(justify left)
			)
		)
		(property "Value" "C_22u_25V_0805"
			(at 389.89 219.71 0)
			(effects
				(font
					(size 1.27 1.27)
					(thickness 0.15)
				)
				(justify left bottom)
				(hide yes)
			)
		)
		(property "Footprint" "antmicro-footprints:C_0805_2012Metric"
			(at 392.43 219.71 0)
			(effects
				(font
					(size 1.27 1.27)
					(thickness 0.15)
				)
				(justify left bottom)
				(hide yes)
			)
		)
		(property "Datasheet" "https://product.samsungsem.com/mlcc/CL21A226MAYNNN.do"
			(at 394.97 219.71 0)
			(effects
				(font
					(size 1.27 1.27)
					(thickness 0.15)
				)
				(justify left bottom)
				(hide yes)
			)
		)
		(property "Description" "SMT Multilayer Ceramic Capacitor, 22uF, +/-20%, 25V, X5R, 0805 [2012 Metric]"
			(at 367.03 234.95 0)
			(effects
				(font
					(size 1.27 1.27)
				)
				(hide yes)
			)
		)
		(property "MPN" "CL21A226MAYNNNE"
			(at 397.51 219.71 0)
			(effects
				(font
					(size 1.27 1.27)
					(thickness 0.15)
				)
				(justify left bottom)
				(hide yes)
			)
		)
		(property "Val" "22u"
			(at 364.49 232.4036 90)
			(effects
				(font
					(size 1.27 1.27)
					(thickness 0.15)
				)
				(justify left)
			)
		)
		(property "Voltage" "25V"
			(at 364.49 234.9436 90)
			(effects
				(font
					(size 1.27 1.27)
					(thickness 0.15)
				)
				(justify left)
			)
		)
		(property "Dielectric" "X5R"
			(at 379.73 219.71 0)
			(effects
				(font
					(size 1.27 1.27)
					(thickness 0.15)
				)
				(justify left bottom)
				(hide yes)
			)
		)
		(property "Manufacturer" "Samsung Electro-Mechanics"
			(at 382.27 219.71 0)
			(effects
				(font
					(size 1.27 1.27)
					(thickness 0.15)
				)
				(justify left bottom)
				(hide yes)
			)
		)
		(property "License" "Apache-2.0"
			(at 384.81 219.71 0)
			(effects
				(font
					(size 1.27 1.27)
					(thickness 0.15)
				)
				(justify left bottom)
				(hide yes)
			)
		)
		(property "Author" "Antmicro"
			(at 387.35 219.71 0)
			(effects
				(font
					(size 1.27 1.27)
					(thickness 0.15)
				)
				(justify left bottom)
				(hide yes)
			)
		)
		(property "Public" "False"
			(at 400.05 214.63 0)
			(effects
				(font
					(size 1.27 1.27)
				)
				(justify left bottom)
				(hide yes)
			)
		)
		(pin "2"
		)
		(pin "1"
		)
		(instances
			(project "jetson-agx-thor-baseboard"
				(path ""
					(reference "C229")
					(unit 1)
				)
			)
		)
	)
	(symbol
		(lib_id "antmicroTestPoints:TP_0.75mm_SMD")
		(at 327.66 29.21 0)
		(mirror y)
		(unit 1)
		(exclude_from_sim no)
		(in_bom no)
		(on_board yes)
		(dnp no)
		(fields_autoplaced yes)
		(property "Reference" "TP73"
			(at 322.58 29.21 0)
			(effects
				(font
					(size 1.27 1.27)
					(thickness 0.15)
				)
				(justify left)
			)
		)
		(property "Value" "TP_0.75mm_SMD"
			(at 317.5 33.02 0)
			(effects
				(font
					(size 1.27 1.27)
					(thickness 0.15)
				)
				(justify left bottom)
				(hide yes)
			)
		)
		(property "Footprint" "antmicro-footprints:TP_SMD_0.75mm"
			(at 317.5 35.56 0)
			(effects
				(font
					(size 1.27 1.27)
					(thickness 0.15)
				)
				(justify left bottom)
				(hide yes)
			)
		)
		(property "Datasheet" ""
			(at 309.88 41.91 0)
			(effects
				(font
					(size 1.27 1.27)
					(thickness 0.15)
				)
				(justify left bottom)
				(hide yes)
			)
		)
		(property "Description" "SMT test point"
			(at 316.865 43.18 0)
			(effects
				(font
					(size 1.27 1.27)
				)
				(justify left bottom)
				(hide yes)
			)
		)
		(property "MPN" ""
			(at 316.865 40.64 0)
			(effects
				(font
					(size 1.27 1.27)
					(thickness 0.15)
				)
				(justify left bottom)
				(hide yes)
			)
		)
		(property "Manufacturer" ""
			(at 316.865 35.56 0)
			(effects
				(font
					(size 1.27 1.27)
					(thickness 0.15)
				)
				(justify left bottom)
				(hide yes)
			)
		)
		(property "Author" "Antmicro"
			(at 317.5 38.1 0)
			(effects
				(font
					(size 1.27 1.27)
					(thickness 0.15)
				)
				(justify left bottom)
				(hide yes)
			)
		)
		(property "License" "Apache-2.0"
			(at 317.5 40.64 0)
			(effects
				(font
					(size 1.27 1.27)
					(thickness 0.15)
				)
				(justify left bottom)
				(hide yes)
			)
		)
		(pin "1"
		)
		(instances
			(project "jetson-agx-thor-baseboard"
				(path ""
					(reference "TP73")
					(unit 1)
				)
			)
		)
	)
	(symbol
		(lib_id "antmicropower:GND")
		(at 212.09 254 0)
		(mirror y)
		(unit 1)
		(exclude_from_sim no)
		(in_bom yes)
		(on_board yes)
		(dnp no)
		(fields_autoplaced yes)
		(property "Reference" "#PWR0429"
			(at 203.2 256.54 0)
			(effects
				(font
					(size 1.27 1.27)
					(thickness 0.15)
				)
				(justify left bottom)
				(hide yes)
			)
		)
		(property "Value" "GND"
			(at 212.09 259.08 0)
			(effects
				(font
					(size 1.27 1.27)
					(thickness 0.15)
				)
			)
		)
		(property "Footprint" ""
			(at 203.2 261.62 0)
			(effects
				(font
					(size 1.27 1.27)
					(thickness 0.15)
				)
				(justify left bottom)
				(hide yes)
			)
		)
		(property "Datasheet" ""
			(at 203.2 266.7 0)
			(effects
				(font
					(size 1.27 1.27)
					(thickness 0.15)
				)
				(justify left bottom)
				(hide yes)
			)
		)
		(property "Description" ""
			(at 212.09 254 0)
			(effects
				(font
					(size 1.27 1.27)
				)
				(hide yes)
			)
		)
		(property "Author" "Antmicro"
			(at 203.2 261.62 0)
			(effects
				(font
					(size 1.27 1.27)
					(thickness 0.15)
				)
				(justify left bottom)
				(hide yes)
			)
		)
		(property "License" "Apache-2.0"
			(at 203.2 264.16 0)
			(effects
				(font
					(size 1.27 1.27)
					(thickness 0.15)
				)
				(justify left bottom)
				(hide yes)
			)
		)
		(pin "1"
		)
		(instances
			(project "jetson-agx-thor-baseboard"
				(path ""
					(reference "#PWR0429")
					(unit 1)
				)
			)
		)
	)
	(symbol
		(lib_id "antmicroResistors0402:R_100R_0402")
		(at 85.09 31.75 0)
		(mirror y)
		(unit 1)
		(exclude_from_sim no)
		(in_bom yes)
		(on_board yes)
		(dnp no)
		(property "Reference" "R350"
			(at 77.724 30.48 0)
			(effects
				(font
					(size 1.27 1.27)
					(thickness 0.15)
				)
			)
		)
		(property "Value" "R_100R_0402"
			(at 64.77 44.45 0)
			(effects
				(font
					(size 1.27 1.27)
					(thickness 0.15)
				)
				(justify left bottom)
				(hide yes)
			)
		)
		(property "Footprint" "antmicro-footprints:R_0402_1005Metric"
			(at 64.77 46.99 0)
			(effects
				(font
					(size 1.27 1.27)
					(thickness 0.15)
				)
				(justify left bottom)
				(hide yes)
			)
		)
		(property "Datasheet" "https://www.bourns.com/docs/product-datasheets/cr.pdf"
			(at 64.77 49.53 0)
			(effects
				(font
					(size 1.27 1.27)
					(thickness 0.15)
				)
				(justify left bottom)
				(hide yes)
			)
		)
		(property "Description" "SMD Chip Resistor, 100 ohm, ± 1%, 62.5 mW, 0402 [1005 Metric], Thick Film, General Purpose"
			(at 64.77 62.23 0)
			(effects
				(font
					(size 1.27 1.27)
				)
				(justify left bottom)
				(hide yes)
			)
		)
		(property "MPN" "CR0402-FX-1000GLF"
			(at 64.77 52.07 0)
			(effects
				(font
					(size 1.27 1.27)
					(thickness 0.15)
				)
				(justify left bottom)
				(hide yes)
			)
		)
		(property "Manufacturer" "Bourns"
			(at 64.77 54.61 0)
			(effects
				(font
					(size 1.27 1.27)
					(thickness 0.15)
				)
				(justify left bottom)
				(hide yes)
			)
		)
		(property "License" "Apache-2.0"
			(at 64.77 57.15 0)
			(effects
				(font
					(size 1.27 1.27)
					(thickness 0.15)
				)
				(justify left bottom)
				(hide yes)
			)
		)
		(property "Author" "Antmicro"
			(at 64.77 59.69 0)
			(effects
				(font
					(size 1.27 1.27)
					(thickness 0.15)
				)
				(justify left bottom)
				(hide yes)
			)
		)
		(property "Val" "100R"
			(at 77.978 33.02 0)
			(effects
				(font
					(size 1.27 1.27)
					(thickness 0.15)
				)
			)
		)
		(property "Tolerance" "1%"
			(at 64.77 41.91 0)
			(effects
				(font
					(size 1.27 1.27)
				)
				(justify left bottom)
				(hide yes)
			)
		)
		(pin "1"
		)
		(pin "2"
		)
		(instances
			(project ""
				(path ""
					(reference "R350")
					(unit 1)
				)
			)
		)
	)
	(symbol
		(lib_id "antmicropower:GND")
		(at 181.61 158.75 0)
		(mirror y)
		(unit 1)
		(exclude_from_sim no)
		(in_bom yes)
		(on_board yes)
		(dnp no)
		(fields_autoplaced yes)
		(property "Reference" "#PWR013"
			(at 172.72 161.29 0)
			(effects
				(font
					(size 1.27 1.27)
					(thickness 0.15)
				)
				(justify left bottom)
				(hide yes)
			)
		)
		(property "Value" "GND"
			(at 181.61 163.83 0)
			(effects
				(font
					(size 1.27 1.27)
					(thickness 0.15)
				)
			)
		)
		(property "Footprint" ""
			(at 172.72 166.37 0)
			(effects
				(font
					(size 1.27 1.27)
					(thickness 0.15)
				)
				(justify left bottom)
				(hide yes)
			)
		)
		(property "Datasheet" ""
			(at 172.72 171.45 0)
			(effects
				(font
					(size 1.27 1.27)
					(thickness 0.15)
				)
				(justify left bottom)
				(hide yes)
			)
		)
		(property "Description" ""
			(at 172.72 173.99 0)
			(effects
				(font
					(size 1.27 1.27)
				)
				(justify left bottom)
				(hide yes)
			)
		)
		(property "Author" "Antmicro"
			(at 172.72 166.37 0)
			(effects
				(font
					(size 1.27 1.27)
					(thickness 0.15)
				)
				(justify left bottom)
				(hide yes)
			)
		)
		(property "License" "Apache-2.0"
			(at 172.72 168.91 0)
			(effects
				(font
					(size 1.27 1.27)
					(thickness 0.15)
				)
				(justify left bottom)
				(hide yes)
			)
		)
		(pin "1"
		)
		(instances
			(project ""
				(path ""
					(reference "#PWR013")
					(unit 1)
				)
			)
		)
	)
	(symbol
		(lib_id "antmicropower:+1V8")
		(at 72.39 24.13 0)
		(mirror y)
		(unit 1)
		(exclude_from_sim no)
		(in_bom yes)
		(on_board yes)
		(dnp no)
		(property "Reference" "#PWR0127"
			(at 72.39 27.94 0)
			(effects
				(font
					(size 1.27 1.27)
				)
				(justify left bottom)
				(hide yes)
			)
		)
		(property "Value" "+1V8"
			(at 75.565 20.32 0)
			(effects
				(font
					(size 1.27 1.27)
					(thickness 0.15)
				)
				(justify left)
			)
		)
		(property "Footprint" ""
			(at 57.15 31.75 0)
			(effects
				(font
					(size 1.27 1.27)
					(thickness 0.15)
				)
				(justify left bottom)
				(hide yes)
			)
		)
		(property "Datasheet" ""
			(at 57.15 34.29 0)
			(effects
				(font
					(size 1.27 1.27)
					(thickness 0.15)
				)
				(justify left bottom)
				(hide yes)
			)
		)
		(property "Description" ""
			(at 72.39 24.13 0)
			(effects
				(font
					(size 1.27 1.27)
				)
				(hide yes)
			)
		)
		(property "Author" "Antmicro"
			(at 57.15 29.21 0)
			(effects
				(font
					(size 1.27 1.27)
					(thickness 0.15)
				)
				(justify left bottom)
				(hide yes)
			)
		)
		(property "License" "Apache-2.0"
			(at 57.15 31.75 0)
			(effects
				(font
					(size 1.27 1.27)
					(thickness 0.15)
				)
				(justify left bottom)
				(hide yes)
			)
		)
		(pin "1"
		)
		(instances
			(project "jetson-agx-thor-baseboard"
				(path ""
					(reference "#PWR0127")
					(unit 1)
				)
			)
		)
	)
	(symbol
		(lib_id "antmicroResistors0402:R_0R_0402")
		(at 382.27 246.38 0)
		(unit 1)
		(exclude_from_sim no)
		(in_bom no)
		(on_board yes)
		(dnp yes)
		(property "Reference" "R320"
			(at 384.81 243.84 0)
			(effects
				(font
					(size 1.27 1.27)
					(thickness 0.15)
				)
			)
		)
		(property "Value" "R_0R_0402"
			(at 402.59 259.08 0)
			(effects
				(font
					(size 1.27 1.27)
					(thickness 0.15)
				)
				(justify left bottom)
				(hide yes)
			)
		)
		(property "Footprint" "antmicro-footprints:R_0402_1005Metric"
			(at 402.59 261.62 0)
			(effects
				(font
					(size 1.27 1.27)
					(thickness 0.15)
				)
				(justify left bottom)
				(hide yes)
			)
		)
		(property "Datasheet" "https://industrial.panasonic.com/cdbs/www-data/pdf/RDA0000/AOA0000C301.pdf"
			(at 402.59 264.16 0)
			(effects
				(font
					(size 1.27 1.27)
					(thickness 0.15)
				)
				(justify left bottom)
				(hide yes)
			)
		)
		(property "Description" "SMD Chip Resistor, Jumper, 0 ohm, 100 mW, 0402 [1005 Metric], Thick Film, General Purpose"
			(at 402.59 279.4 0)
			(effects
				(font
					(size 1.27 1.27)
				)
				(justify left bottom)
				(hide yes)
			)
		)
		(property "MPN" "ERJ2GE0R00X"
			(at 402.59 266.7 0)
			(effects
				(font
					(size 1.27 1.27)
					(thickness 0.15)
				)
				(justify left bottom)
				(hide yes)
			)
		)
		(property "Manufacturer" "Panasonic"
			(at 402.59 269.24 0)
			(effects
				(font
					(size 1.27 1.27)
					(thickness 0.15)
				)
				(justify left bottom)
				(hide yes)
			)
		)
		(property "License" "Apache-2.0"
			(at 402.59 271.78 0)
			(effects
				(font
					(size 1.27 1.27)
					(thickness 0.15)
				)
				(justify left bottom)
				(hide yes)
			)
		)
		(property "Author" "Antmicro"
			(at 402.59 274.32 0)
			(effects
				(font
					(size 1.27 1.27)
					(thickness 0.15)
				)
				(justify left bottom)
				(hide yes)
			)
		)
		(property "Val" "0R"
			(at 384.81 249.428 0)
			(effects
				(font
					(size 1.27 1.27)
					(thickness 0.15)
				)
			)
		)
		(property "Tolerance" "~"
			(at 402.59 256.54 0)
			(effects
				(font
					(size 1.27 1.27)
				)
				(justify left bottom)
				(hide yes)
			)
		)
		(property "Current" "1A"
			(at 402.59 276.86 0)
			(effects
				(font
					(size 1.27 1.27)
					(thickness 0.15)
				)
				(justify left bottom)
				(hide yes)
			)
		)
		(pin "2"
		)
		(pin "1"
		)
		(instances
			(project ""
				(path ""
					(reference "R320")
					(unit 1)
				)
			)
		)
	)
	(symbol
		(lib_id "antmicroCapacitors0402:C_220n_0402")
		(at 269.24 237.49 0)
		(mirror y)
		(unit 1)
		(exclude_from_sim no)
		(in_bom yes)
		(on_board yes)
		(dnp no)
		(fields_autoplaced yes)
		(property "Reference" "C211"
			(at 270.256 236.22 0)
			(effects
				(font
					(size 1.27 1.27)
					(thickness 0.15)
				)
			)
		)
		(property "Value" "C_220n_0402"
			(at 254 260.35 0)
			(effects
				(font
					(size 1.27 1.27)
					(thickness 0.15)
				)
				(justify left bottom)
				(hide yes)
			)
		)
		(property "Footprint" "antmicro-footprints:C_0402_1005Metric"
			(at 254 262.89 0)
			(effects
				(font
					(size 1.27 1.27)
					(thickness 0.15)
				)
				(justify left bottom)
				(hide yes)
			)
		)
		(property "Datasheet" "https://www.yageo.com/en/Chart/Download/pdf/CC0402KRX5R6BB224"
			(at 254 265.43 0)
			(effects
				(font
					(size 1.27 1.27)
					(thickness 0.15)
				)
				(justify left bottom)
				(hide yes)
			)
		)
		(property "Description" "SMD Multilayer Ceramic Capacitor, 0.22 µF, 10 V, 0402 [1005 Metric], ± 10%, X5R, CC Series"
			(at 269.24 237.49 0)
			(effects
				(font
					(size 1.27 1.27)
				)
				(hide yes)
			)
		)
		(property "MPN" "CC0402KRX5R6BB224"
			(at 254 267.97 0)
			(effects
				(font
					(size 1.27 1.27)
					(thickness 0.15)
				)
				(justify left bottom)
				(hide yes)
			)
		)
		(property "Val" "220n"
			(at 262.89 236.22 0)
			(effects
				(font
					(size 1.27 1.27)
					(thickness 0.15)
				)
			)
		)
		(property "Voltage" "25V"
			(at 254 247.65 0)
			(effects
				(font
					(size 1.27 1.27)
					(thickness 0.15)
				)
				(justify left bottom)
				(hide yes)
			)
		)
		(property "Dielectric" "X7R"
			(at 254 250.19 0)
			(effects
				(font
					(size 1.27 1.27)
					(thickness 0.15)
				)
				(justify left bottom)
				(hide yes)
			)
		)
		(property "Manufacturer" "YAGEO"
			(at 254 252.73 0)
			(effects
				(font
					(size 1.27 1.27)
					(thickness 0.15)
				)
				(justify left bottom)
				(hide yes)
			)
		)
		(property "License" "Apache-2.0"
			(at 254 255.27 0)
			(effects
				(font
					(size 1.27 1.27)
					(thickness 0.15)
				)
				(justify left bottom)
				(hide yes)
			)
		)
		(property "Author" "Antmicro"
			(at 254 257.81 0)
			(effects
				(font
					(size 1.27 1.27)
					(thickness 0.15)
				)
				(justify left bottom)
				(hide yes)
			)
		)
		(property "Public" "False"
			(at 248.92 270.51 0)
			(effects
				(font
					(size 1.27 1.27)
				)
				(justify left bottom)
				(hide yes)
			)
		)
		(pin "2"
		)
		(pin "1"
		)
		(instances
			(project "jetson-agx-thor-baseboard"
				(path ""
					(reference "C211")
					(unit 1)
				)
			)
		)
	)
	(symbol
		(lib_id "antmicroMemory:AT24CS01_SOIC8")
		(at 335.28 176.53 0)
		(unit 1)
		(exclude_from_sim no)
		(in_bom yes)
		(on_board yes)
		(dnp no)
		(property "Reference" "U2"
			(at 343.154 169.926 0)
			(effects
				(font
					(size 1.27 1.27)
					(thickness 0.15)
				)
			)
		)
		(property "Value" "AT24CS01_SOIC8"
			(at 370.84 181.61 0)
			(effects
				(font
					(size 1.27 1.27)
					(thickness 0.15)
				)
				(justify left bottom)
				(hide yes)
			)
		)
		(property "Footprint" "antmicro-footprints:SOIC-8_3.9x4.9x1.75mm_P1.27mm"
			(at 370.84 184.15 0)
			(effects
				(font
					(size 1.27 1.27)
					(thickness 0.15)
				)
				(justify left bottom)
				(hide yes)
			)
		)
		(property "Datasheet" "https://ww1.microchip.com/downloads/aemDocuments/documents/MPD/ProductDocuments/DataSheets/20006330A.pdf"
			(at 370.84 186.69 0)
			(effects
				(font
					(size 1.27 1.27)
					(thickness 0.15)
				)
				(justify left bottom)
				(hide yes)
			)
		)
		(property "Description" "EEPROM, 1 Kbit, 128 x 8bit, Serial I2C (2-Wire), 1 MHz, SOIC-8"
			(at 370.84 199.39 0)
			(effects
				(font
					(size 1.27 1.27)
				)
				(justify left bottom)
				(hide yes)
			)
		)
		(property "Manufacturer" "Microchip Technology"
			(at 370.84 189.23 0)
			(effects
				(font
					(size 1.27 1.27)
					(thickness 0.15)
				)
				(justify left bottom)
				(hide yes)
			)
		)
		(property "MPN" "AT24CS01-SSHM-B"
			(at 343.154 172.466 0)
			(effects
				(font
					(size 1.27 1.27)
					(thickness 0.15)
				)
			)
		)
		(property "Author" "Antmicro"
			(at 370.84 194.31 0)
			(effects
				(font
					(size 1.27 1.27)
					(thickness 0.15)
				)
				(justify left bottom)
				(hide yes)
			)
		)
		(property "License" "Apache-2.0"
			(at 370.84 196.85 0)
			(effects
				(font
					(size 1.27 1.27)
					(thickness 0.15)
				)
				(justify left bottom)
				(hide yes)
			)
		)
		(pin "4"
		)
		(pin "5"
		)
		(pin "1"
		)
		(pin "3"
		)
		(pin "2"
		)
		(pin "7"
		)
		(pin "6"
		)
		(pin "8"
		)
		(instances
			(project "jetson-agx-thor-baseboard"
				(path ""
					(reference "U2")
					(unit 1)
				)
			)
		)
	)
	(symbol
		(lib_id "antmicroResistors0603:R_0R_22.4A_0603")
		(at 382.27 236.22 0)
		(unit 1)
		(exclude_from_sim no)
		(in_bom no)
		(on_board yes)
		(dnp yes)
		(property "Reference" "R249"
			(at 384.81 234.315 0)
			(effects
				(font
					(size 1.27 1.27)
					(thickness 0.15)
				)
			)
		)
		(property "Value" "R_0R_22.4A_0603"
			(at 384.81 227.33 0)
			(effects
				(font
					(size 1.27 1.27)
					(thickness 0.15)
				)
				(hide yes)
			)
		)
		(property "Footprint" "antmicro-footprints:R_0603_1608Metric"
			(at 397.51 246.38 0)
			(effects
				(font
					(size 1.27 1.27)
					(thickness 0.15)
				)
				(justify left bottom)
				(hide yes)
			)
		)
		(property "Datasheet" "https://fscdn.rohm.com/en/products/databook/datasheet/passive/resistor/chip_resistor/pmr-jpw-e.pdf"
			(at 397.51 248.92 0)
			(effects
				(font
					(size 1.27 1.27)
					(thickness 0.15)
				)
				(justify left bottom)
				(hide yes)
			)
		)
		(property "Description" "SMD Chip Resistor"
			(at 382.27 236.22 0)
			(effects
				(font
					(size 1.27 1.27)
				)
				(hide yes)
			)
		)
		(property "MPN" "PMR03EZPJ000"
			(at 397.51 251.46 0)
			(effects
				(font
					(size 1.27 1.27)
					(thickness 0.15)
				)
				(justify left bottom)
				(hide yes)
			)
		)
		(property "Manufacturer" "ROHM Semiconductor"
			(at 397.51 254 0)
			(effects
				(font
					(size 1.27 1.27)
					(thickness 0.15)
				)
				(justify left bottom)
				(hide yes)
			)
		)
		(property "Val" "0R"
			(at 387.35 238.76 0)
			(effects
				(font
					(size 1.27 1.27)
					(thickness 0.15)
				)
			)
		)
		(property "Max. Curr." "22.4A"
			(at 382.27 238.76 0)
			(effects
				(font
					(size 1.27 1.27)
					(thickness 0.15)
				)
			)
		)
		(property "Author" "Antmicro"
			(at 397.51 259.08 0)
			(effects
				(font
					(size 1.27 1.27)
					(thickness 0.15)
				)
				(justify left bottom)
				(hide yes)
			)
		)
		(property "License" "Apache-2.0"
			(at 397.51 261.62 0)
			(effects
				(font
					(size 1.27 1.27)
					(thickness 0.15)
				)
				(justify left bottom)
				(hide yes)
			)
		)
		(property "Tolerance" "template_tolerance"
			(at 402.59 246.38 0)
			(effects
				(font
					(size 1.27 1.27)
				)
				(justify left bottom)
				(hide yes)
			)
		)
		(pin "1"
		)
		(pin "2"
		)
		(instances
			(project "jetson-agx-thor-baseboard"
				(path ""
					(reference "R249")
					(unit 1)
				)
			)
		)
	)
	(symbol
		(lib_id "antmicropower:+3V3")
		(at 379.73 245.11 0)
		(mirror y)
		(unit 1)
		(exclude_from_sim no)
		(in_bom yes)
		(on_board yes)
		(dnp no)
		(property "Reference" "#PWR07"
			(at 364.49 245.11 0)
			(effects
				(font
					(size 1.27 1.27)
					(thickness 0.15)
				)
				(justify left bottom)
				(hide yes)
			)
		)
		(property "Value" "+3V3"
			(at 379.984 241.3 0)
			(effects
				(font
					(size 1.27 1.27)
					(thickness 0.15)
				)
			)
		)
		(property "Footprint" ""
			(at 364.49 252.73 0)
			(effects
				(font
					(size 1.27 1.27)
					(thickness 0.15)
				)
				(justify left bottom)
				(hide yes)
			)
		)
		(property "Datasheet" ""
			(at 364.49 255.27 0)
			(effects
				(font
					(size 1.27 1.27)
					(thickness 0.15)
				)
				(justify left bottom)
				(hide yes)
			)
		)
		(property "Description" ""
			(at 379.73 245.11 0)
			(effects
				(font
					(size 1.27 1.27)
				)
				(hide yes)
			)
		)
		(property "Author" "Antmicro"
			(at 364.49 247.65 0)
			(effects
				(font
					(size 1.27 1.27)
					(thickness 0.15)
				)
				(justify left bottom)
				(hide yes)
			)
		)
		(property "License" "Apache-2.0"
			(at 364.49 250.19 0)
			(effects
				(font
					(size 1.27 1.27)
					(thickness 0.15)
				)
				(justify left bottom)
				(hide yes)
			)
		)
		(pin "1"
		)
		(instances
			(project "jetson-agx-thor-baseboard"
				(path ""
					(reference "#PWR07")
					(unit 1)
				)
			)
		)
	)
	(symbol
		(lib_id "antmicropower:GND")
		(at 97.79 250.19 0)
		(mirror y)
		(unit 1)
		(exclude_from_sim no)
		(in_bom yes)
		(on_board yes)
		(dnp no)
		(property "Reference" "#PWR0433"
			(at 88.9 252.73 0)
			(effects
				(font
					(size 1.27 1.27)
					(thickness 0.15)
				)
				(justify left bottom)
				(hide yes)
			)
		)
		(property "Value" "GND"
			(at 97.79 254 0)
			(effects
				(font
					(size 1.27 1.27)
					(thickness 0.15)
				)
			)
		)
		(property "Footprint" ""
			(at 88.9 257.81 0)
			(effects
				(font
					(size 1.27 1.27)
					(thickness 0.15)
				)
				(justify left bottom)
				(hide yes)
			)
		)
		(property "Datasheet" ""
			(at 88.9 262.89 0)
			(effects
				(font
					(size 1.27 1.27)
					(thickness 0.15)
				)
				(justify left bottom)
				(hide yes)
			)
		)
		(property "Description" ""
			(at 97.79 250.19 0)
			(effects
				(font
					(size 1.27 1.27)
				)
				(hide yes)
			)
		)
		(property "Author" "Antmicro"
			(at 88.9 257.81 0)
			(effects
				(font
					(size 1.27 1.27)
					(thickness 0.15)
				)
				(justify left bottom)
				(hide yes)
			)
		)
		(property "License" "Apache-2.0"
			(at 88.9 260.35 0)
			(effects
				(font
					(size 1.27 1.27)
					(thickness 0.15)
				)
				(justify left bottom)
				(hide yes)
			)
		)
		(pin "1"
		)
		(instances
			(project "jetson-agx-thor-baseboard"
				(path ""
					(reference "#PWR0433")
					(unit 1)
				)
			)
		)
	)
	(symbol
		(lib_id "antmicroCapacitors0402:C_100n_0402")
		(at 358.14 185.42 90)
		(unit 1)
		(exclude_from_sim no)
		(in_bom yes)
		(on_board yes)
		(dnp no)
		(fields_autoplaced yes)
		(property "Reference" "C5"
			(at 360.68 181.6036 90)
			(effects
				(font
					(size 1.27 1.27)
					(thickness 0.15)
				)
				(justify right)
			)
		)
		(property "Value" "C_100n_0402"
			(at 368.3 165.1 0)
			(effects
				(font
					(size 1.27 1.27)
					(thickness 0.15)
				)
				(justify left bottom)
				(hide yes)
			)
		)
		(property "Footprint" "antmicro-footprints:C_0402_1005Metric"
			(at 370.84 165.1 0)
			(effects
				(font
					(size 1.27 1.27)
					(thickness 0.15)
				)
				(justify left bottom)
				(hide yes)
			)
		)
		(property "Datasheet" "https://www.murata.com/products/productdetail?partno=GRM155R61H104KE14%23"
			(at 373.38 165.1 0)
			(effects
				(font
					(size 1.27 1.27)
					(thickness 0.15)
				)
				(justify left bottom)
				(hide yes)
			)
		)
		(property "Description" "SMD Multilayer Ceramic Capacitor, 0.1 µF, 50 V, 0402 [1005 Metric], ± 10%, X5R, GRM Series"
			(at 358.14 185.42 0)
			(effects
				(font
					(size 1.27 1.27)
				)
				(hide yes)
			)
		)
		(property "MPN" "GRM155R61H104KE14D"
			(at 375.92 165.1 0)
			(effects
				(font
					(size 1.27 1.27)
					(thickness 0.15)
				)
				(justify left bottom)
				(hide yes)
			)
		)
		(property "Manufacturer" "Murata"
			(at 378.46 165.1 0)
			(effects
				(font
					(size 1.27 1.27)
					(thickness 0.15)
				)
				(justify left bottom)
				(hide yes)
			)
		)
		(property "License" "Apache-2.0"
			(at 381 165.1 0)
			(effects
				(font
					(size 1.27 1.27)
					(thickness 0.15)
				)
				(justify left bottom)
				(hide yes)
			)
		)
		(property "Author" "Antmicro"
			(at 383.54 165.1 0)
			(effects
				(font
					(size 1.27 1.27)
					(thickness 0.15)
				)
				(justify left bottom)
				(hide yes)
			)
		)
		(property "Val" "100n"
			(at 360.68 184.1436 90)
			(effects
				(font
					(size 1.27 1.27)
					(thickness 0.15)
				)
				(justify right)
			)
		)
		(property "Voltage" "50V"
			(at 386.08 165.1 0)
			(effects
				(font
					(size 1.27 1.27)
				)
				(justify left bottom)
				(hide yes)
			)
		)
		(property "Dielectric" "X5R"
			(at 388.62 165.1 0)
			(effects
				(font
					(size 1.27 1.27)
				)
				(justify left bottom)
				(hide yes)
			)
		)
		(pin "2"
		)
		(pin "1"
		)
		(instances
			(project "jetson-agx-thor-baseboard"
				(path ""
					(reference "C5")
					(unit 1)
				)
			)
		)
	)
	(symbol
		(lib_id "antmicropower:GND")
		(at 349.25 236.22 0)
		(mirror y)
		(unit 1)
		(exclude_from_sim no)
		(in_bom yes)
		(on_board yes)
		(dnp no)
		(property "Reference" "#PWR0449"
			(at 340.36 238.76 0)
			(effects
				(font
					(size 1.27 1.27)
					(thickness 0.15)
				)
				(justify left bottom)
				(hide yes)
			)
		)
		(property "Value" "GND"
			(at 349.25 240.03 0)
			(effects
				(font
					(size 1.27 1.27)
					(thickness 0.15)
				)
			)
		)
		(property "Footprint" ""
			(at 340.36 243.84 0)
			(effects
				(font
					(size 1.27 1.27)
					(thickness 0.15)
				)
				(justify left bottom)
				(hide yes)
			)
		)
		(property "Datasheet" ""
			(at 340.36 248.92 0)
			(effects
				(font
					(size 1.27 1.27)
					(thickness 0.15)
				)
				(justify left bottom)
				(hide yes)
			)
		)
		(property "Description" ""
			(at 349.25 236.22 0)
			(effects
				(font
					(size 1.27 1.27)
				)
				(hide yes)
			)
		)
		(property "Author" "Antmicro"
			(at 340.36 243.84 0)
			(effects
				(font
					(size 1.27 1.27)
					(thickness 0.15)
				)
				(justify left bottom)
				(hide yes)
			)
		)
		(property "License" "Apache-2.0"
			(at 340.36 246.38 0)
			(effects
				(font
					(size 1.27 1.27)
					(thickness 0.15)
				)
				(justify left bottom)
				(hide yes)
			)
		)
		(pin "1"
		)
		(instances
			(project "jetson-agx-thor-baseboard"
				(path ""
					(reference "#PWR0449")
					(unit 1)
				)
			)
		)
	)
	(symbol
		(lib_id "antmicroTestPoints:TP_0.75mm_SMD")
		(at 83.82 29.21 0)
		(mirror y)
		(unit 1)
		(exclude_from_sim no)
		(in_bom no)
		(on_board yes)
		(dnp no)
		(property "Reference" "TP109"
			(at 81.534 27.432 0)
			(effects
				(font
					(size 1.27 1.27)
					(thickness 0.15)
				)
				(justify left)
			)
		)
		(property "Value" "TP_0.75mm_SMD"
			(at 73.66 33.02 0)
			(effects
				(font
					(size 1.27 1.27)
					(thickness 0.15)
				)
				(justify left bottom)
				(hide yes)
			)
		)
		(property "Footprint" "antmicro-footprints:TP_SMD_0.75mm"
			(at 73.66 35.56 0)
			(effects
				(font
					(size 1.27 1.27)
					(thickness 0.15)
				)
				(justify left bottom)
				(hide yes)
			)
		)
		(property "Datasheet" ""
			(at 66.04 41.91 0)
			(effects
				(font
					(size 1.27 1.27)
					(thickness 0.15)
				)
				(justify left bottom)
				(hide yes)
			)
		)
		(property "Description" "SMT test point"
			(at 73.025 43.18 0)
			(effects
				(font
					(size 1.27 1.27)
				)
				(justify left bottom)
				(hide yes)
			)
		)
		(property "MPN" ""
			(at 73.025 40.64 0)
			(effects
				(font
					(size 1.27 1.27)
					(thickness 0.15)
				)
				(justify left bottom)
				(hide yes)
			)
		)
		(property "Manufacturer" ""
			(at 73.025 35.56 0)
			(effects
				(font
					(size 1.27 1.27)
					(thickness 0.15)
				)
				(justify left bottom)
				(hide yes)
			)
		)
		(property "Author" "Antmicro"
			(at 73.66 38.1 0)
			(effects
				(font
					(size 1.27 1.27)
					(thickness 0.15)
				)
				(justify left bottom)
				(hide yes)
			)
		)
		(property "License" "Apache-2.0"
			(at 73.66 40.64 0)
			(effects
				(font
					(size 1.27 1.27)
					(thickness 0.15)
				)
				(justify left bottom)
				(hide yes)
			)
		)
		(pin "1"
		)
		(instances
			(project "jetson-agx-thor-baseboard"
				(path ""
					(reference "TP109")
					(unit 1)
				)
			)
		)
	)
	(symbol
		(lib_id "antmicroB2BConnectors:ASP-208571-01_mounting_holes")
		(at 109.22 29.21 0)
		(mirror y)
		(unit 5)
		(exclude_from_sim no)
		(in_bom yes)
		(on_board yes)
		(dnp no)
		(fields_autoplaced yes)
		(property "Reference" "J18"
			(at 97.79 21.59 0)
			(effects
				(font
					(size 1.27 1.27)
					(thickness 0.15)
				)
			)
		)
		(property "Value" "ASP-208571-01_mounting_holes"
			(at 72.39 39.37 0)
			(effects
				(font
					(size 1.27 1.27)
					(thickness 0.15)
				)
				(justify left bottom)
				(hide yes)
			)
		)
		(property "Footprint" "antmicro-footprints:ASP-208571-01_mounting_holes"
			(at 72.39 41.91 0)
			(effects
				(font
					(size 1.27 1.27)
					(thickness 0.15)
				)
				(justify left bottom)
				(hide yes)
			)
		)
		(property "Datasheet" "https://suddendocs.samtec.com/prints/asp-208571-01-mkt.pdf"
			(at 72.39 44.45 0)
			(effects
				(font
					(size 1.27 1.27)
					(thickness 0.15)
				)
				(justify left bottom)
				(hide yes)
			)
		)
		(property "Description" "FMC connector"
			(at 72.39 54.61 0)
			(effects
				(font
					(size 1.27 1.27)
				)
				(justify left bottom)
				(hide yes)
			)
		)
		(property "MPN" "ASP-208571-01"
			(at 97.79 24.13 0)
			(effects
				(font
					(size 1.27 1.27)
					(thickness 0.15)
				)
			)
		)
		(property "Manufacturer" "Samtec"
			(at 72.39 46.99 0)
			(effects
				(font
					(size 1.27 1.27)
					(thickness 0.15)
				)
				(justify left bottom)
				(hide yes)
			)
		)
		(property "Author" "Antmicro"
			(at 72.39 49.53 0)
			(effects
				(font
					(size 1.27 1.27)
					(thickness 0.15)
				)
				(justify left bottom)
				(hide yes)
			)
		)
		(property "License" "Apache-2.0"
			(at 72.39 52.07 0)
			(effects
				(font
					(size 1.27 1.27)
					(thickness 0.15)
				)
				(justify left bottom)
				(hide yes)
			)
		)
		(pin "A40"
		)
		(pin "Z01"
		)
		(pin "A09"
		)
		(pin "Y28"
		)
		(pin "D27"
		)
		(pin "B33"
		)
		(pin "C25"
		)
		(pin "C20"
		)
		(pin "Z05"
		)
		(pin "A10"
		)
		(pin "B14"
		)
		(pin "Y39"
		)
		(pin "C36"
		)
		(pin "F14"
		)
		(pin "H02"
		)
		(pin "H03"
		)
		(pin "A28"
		)
		(pin "C37"
		)
		(pin "A26"
		)
		(pin "C19"
		)
		(pin "Z06"
		)
		(pin "C28"
		)
		(pin "B10"
		)
		(pin "Z27"
		)
		(pin "B40"
		)
		(pin "Z28"
		)
		(pin "Z26"
		)
		(pin "C24"
		)
		(pin "B09"
		)
		(pin "Y27"
		)
		(pin "C08"
		)
		(pin "Z04"
		)
		(pin "A36"
		)
		(pin "C02"
		)
		(pin "A19"
		)
		(pin "E34"
		)
		(pin "K28"
		)
		(pin "K29"
		)
		(pin "G20"
		)
		(pin "G21"
		)
		(pin "A08"
		)
		(pin "B27"
		)
		(pin "D22"
		)
		(pin "F25"
		)
		(pin "C30"
		)
		(pin "D04"
		)
		(pin "A30"
		)
		(pin "A38"
		)
		(pin "B37"
		)
		(pin "G26"
		)
		(pin "G27"
		)
		(pin "C03"
		)
		(pin "F07"
		)
		(pin "D34"
		)
		(pin "G08"
		)
		(pin "G18"
		)
		(pin "G19"
		)
		(pin "G01"
		)
		(pin "A20"
		)
		(pin "M04"
		)
		(pin "M05"
		)
		(pin "Y08"
		)
		(pin "F39"
		)
		(pin "F19"
		)
		(pin "K04"
		)
		(pin "K05"
		)
		(pin "G12"
		)
		(pin "G13"
		)
		(pin "Y02"
		)
		(pin "J32"
		)
		(pin "J33"
		)
		(pin "B11"
		)
		(pin "D07"
		)
		(pin "C33"
		)
		(pin "A17"
		)
		(pin "D14"
		)
		(pin "A15"
		)
		(pin "B39"
		)
		(pin "A18"
		)
		(pin "B21"
		)
		(pin "D11"
		)
		(pin "Y15"
		)
		(pin "B16"
		)
		(pin "Y09"
		)
		(pin "F29"
		)
		(pin "J30"
		)
		(pin "J31"
		)
		(pin "B19"
		)
		(pin "A05"
		)
		(pin "B38"
		)
		(pin "E22"
		)
		(pin "D15"
		)
		(pin "L02"
		)
		(pin "L03"
		)
		(pin "Y37"
		)
		(pin "E07"
		)
		(pin "A22"
		)
		(pin "H20"
		)
		(pin "H21"
		)
		(pin "Z39"
		)
		(pin "F37"
		)
		(pin "B30"
		)
		(pin "Z15"
		)
		(pin "H36"
		)
		(pin "H37"
		)
		(pin "D16"
		)
		(pin "D37"
		)
		(pin "C40"
		)
		(pin "E29"
		)
		(pin "Y36"
		)
		(pin "K10"
		)
		(pin "K11"
		)
		(pin "F38"
		)
		(pin "B04"
		)
		(pin "F15"
		)
		(pin "J28"
		)
		(pin "J29"
		)
		(pin "B17"
		)
		(pin "E37"
		)
		(pin "E09"
		)
		(pin "Z23"
		)
		(pin "J06"
		)
		(pin "J07"
		)
		(pin "Z30"
		)
		(pin "C31"
		)
		(pin "Z37"
		)
		(pin "Z33"
		)
		(pin "Z29"
		)
		(pin "Y26"
		)
		(pin "H06"
		)
		(pin "H07"
		)
		(pin "C10"
		)
		(pin "F27"
		)
		(pin "A03"
		)
		(pin "M10"
		)
		(pin "M11"
		)
		(pin "M12"
		)
		(pin "L04"
		)
		(pin "L05"
		)
		(pin "A24"
		)
		(pin "M28"
		)
		(pin "M29"
		)
		(pin "M30"
		)
		(pin "D32"
		)
		(pin "H18"
		)
		(pin "H19"
		)
		(pin "F03"
		)
		(pin "L08"
		)
		(pin "L09"
		)
		(pin "A01"
		)
		(pin "B32"
		)
		(pin "K36"
		)
		(pin "K37"
		)
		(pin "C01"
		)
		(pin "D18"
		)
		(pin "E12"
		)
		(pin "K16"
		)
		(pin "K17"
		)
		(pin "Y11"
		)
		(pin "B31"
		)
		(pin "D28"
		)
		(pin "D23"
		)
		(pin "Z18"
		)
		(pin "D17"
		)
		(pin "F32"
		)
		(pin "B20"
		)
		(pin "C18"
		)
		(pin "A25"
		)
		(pin "Y05"
		)
		(pin "J26"
		)
		(pin "J27"
		)
		(pin "Y33"
		)
		(pin "A37"
		)
		(pin "Z21"
		)
		(pin "D09"
		)
		(pin "B26"
		)
		(pin "A35"
		)
		(pin "D20"
		)
		(pin "A11"
		)
		(pin "C15"
		)
		(pin "G14"
		)
		(pin "G15"
		)
		(pin "D01"
		)
		(pin "D21"
		)
		(pin "M34"
		)
		(pin "M35"
		)
		(pin "M36"
		)
		(pin "L32"
		)
		(pin "L33"
		)
		(pin "D31"
		)
		(pin "Z07"
		)
		(pin "M31"
		)
		(pin "M32"
		)
		(pin "M33"
		)
		(pin "K18"
		)
		(pin "K19"
		)
		(pin "F06"
		)
		(pin "Z16"
		)
		(pin "H32"
		)
		(pin "H33"
		)
		(pin "Z36"
		)
		(pin "F05"
		)
		(pin "F02"
		)
		(pin "E05"
		)
		(pin "F40"
		)
		(pin "E39"
		)
		(pin "H08"
		)
		(pin "H09"
		)
		(pin "B02"
		)
		(pin "E16"
		)
		(pin "E38"
		)
		(pin "Z12"
		)
		(pin "A34"
		)
		(pin "K08"
		)
		(pin "K09"
		)
		(pin "E31"
		)
		(pin "Y06"
		)
		(pin "F11"
		)
		(pin "F08"
		)
		(pin "A32"
		)
		(pin "Y22"
		)
		(pin "H12"
		)
		(pin "H13"
		)
		(pin "A27"
		)
		(pin "C05"
		)
		(pin "K12"
		)
		(pin "K13"
		)
		(pin "L14"
		)
		(pin "L15"
		)
		(pin "E25"
		)
		(pin "L18"
		)
		(pin "L19"
		)
		(pin "M19"
		)
		(pin "M20"
		)
		(pin "M21"
		)
		(pin "J14"
		)
		(pin "J15"
		)
		(pin "G40"
		)
		(pin "H01"
		)
		(pin "Y25"
		)
		(pin "A33"
		)
		(pin "Z35"
		)
		(pin "H38"
		)
		(pin "H39"
		)
		(pin "D29"
		)
		(pin "E02"
		)
		(pin "D10"
		)
		(pin "C12"
		)
		(pin "C26"
		)
		(pin "M40"
		)
		(pin "B24"
		)
		(pin "Y24"
		)
		(pin "F33"
		)
		(pin "F21"
		)
		(pin "E20"
		)
		(pin "D06"
		)
		(pin "C29"
		)
		(pin "E23"
		)
		(pin "J04"
		)
		(pin "J05"
		)
		(pin "B28"
		)
		(pin "K30"
		)
		(pin "K31"
		)
		(pin "B08"
		)
		(pin "L12"
		)
		(pin "L13"
		)
		(pin "J38"
		)
		(pin "J39"
		)
		(pin "D24"
		)
		(pin "E06"
		)
		(pin "D35"
		)
		(pin "G07"
		)
		(pin "C39"
		)
		(pin "E04"
		)
		(pin "L34"
		)
		(pin "L35"
		)
		(pin "D02"
		)
		(pin "Z22"
		)
		(pin "K14"
		)
		(pin "K15"
		)
		(pin "Y34"
		)
		(pin "M08"
		)
		(pin "M09"
		)
		(pin "D30"
		)
		(pin "G10"
		)
		(pin "G11"
		)
		(pin "C11"
		)
		(pin "E33"
		)
		(pin "G38"
		)
		(pin "G39"
		)
		(pin "F34"
		)
		(pin "H04"
		)
		(pin "H05"
		)
		(pin "F09"
		)
		(pin "G22"
		)
		(pin "G23"
		)
		(pin "B34"
		)
		(pin "Z20"
		)
		(pin "Y03"
		)
		(pin "M06"
		)
		(pin "M07"
		)
		(pin "K38"
		)
		(pin "K39"
		)
		(pin "Y21"
		)
		(pin "K24"
		)
		(pin "K25"
		)
		(pin "E21"
		)
		(pin "L20"
		)
		(pin "L21"
		)
		(pin "E11"
		)
		(pin "K22"
		)
		(pin "K23"
		)
		(pin "B12"
		)
		(pin "J22"
		)
		(pin "J23"
		)
		(pin "A07"
		)
		(pin "E32"
		)
		(pin "L36"
		)
		(pin "L37"
		)
		(pin "L24"
		)
		(pin "L25"
		)
		(pin "Y32"
		)
		(pin "F13"
		)
		(pin "G09"
		)
		(pin "Y01"
		)
		(pin "K06"
		)
		(pin "K07"
		)
		(pin "G28"
		)
		(pin "G29"
		)
		(pin "K40"
		)
		(pin "L01"
		)
		(pin "J02"
		)
		(pin "J03"
		)
		(pin "J12"
		)
		(pin "J13"
		)
		(pin "M25"
		)
		(pin "M26"
		)
		(pin "M27"
		)
		(pin "A13"
		)
		(pin "F20"
		)
		(pin "M37"
		)
		(pin "M38"
		)
		(pin "M39"
		)
		(pin "Y10"
		)
		(pin "G32"
		)
		(pin "G33"
		)
		(pin "A29"
		)
		(pin "L10"
		)
		(pin "L11"
		)
		(pin "G24"
		)
		(pin "G25"
		)
		(pin "E08"
		)
		(pin "C06"
		)
		(pin "A12"
		)
		(pin "F12"
		)
		(pin "C16"
		)
		(pin "Z09"
		)
		(pin "E19"
		)
		(pin "D03"
		)
		(pin "E24"
		)
		(pin "F23"
		)
		(pin "G16"
		)
		(pin "G17"
		)
		(pin "A23"
		)
		(pin "D12"
		)
		(pin "C07"
		)
		(pin "L30"
		)
		(pin "L31"
		)
		(pin "B29"
		)
		(pin "B15"
		)
		(pin "J16"
		)
		(pin "J17"
		)
		(pin "K26"
		)
		(pin "K27"
		)
		(pin "A16"
		)
		(pin "E01"
		)
		(pin "Y12"
		)
		(pin "G04"
		)
		(pin "C32"
		)
		(pin "B22"
		)
		(pin "Y16"
		)
		(pin "G34"
		)
		(pin "G35"
		)
		(pin "A02"
		)
		(pin "D40"
		)
		(pin "Y38"
		)
		(pin "D08"
		)
		(pin "C27"
		)
		(pin "J36"
		)
		(pin "J37"
		)
		(pin "K34"
		)
		(pin "K35"
		)
		(pin "M02"
		)
		(pin "M03"
		)
		(pin "B01"
		)
		(pin "E35"
		)
		(pin "Y13"
		)
		(pin "L26"
		)
		(pin "L27"
		)
		(pin "G36"
		)
		(pin "G37"
		)
		(pin "K32"
		)
		(pin "K33"
		)
		(pin "Y14"
		)
		(pin "D13"
		)
		(pin "D25"
		)
		(pin "F10"
		)
		(pin "E10"
		)
		(pin "E26"
		)
		(pin "E18"
		)
		(pin "F24"
		)
		(pin "Z10"
		)
		(pin "H40"
		)
		(pin "J01"
		)
		(pin "G05"
		)
		(pin "Z17"
		)
		(pin "F22"
		)
		(pin "A14"
		)
		(pin "E30"
		)
		(pin "Z13"
		)
		(pin "H22"
		)
		(pin "H23"
		)
		(pin "E28"
		)
		(pin "F36"
		)
		(pin "B18"
		)
		(pin "Z08"
		)
		(pin "H34"
		)
		(pin "H35"
		)
		(pin "J08"
		)
		(pin "J09"
		)
		(pin "C23"
		)
		(pin "J40"
		)
		(pin "K01"
		)
		(pin "Y07"
		)
		(pin "H14"
		)
		(pin "H15"
		)
		(pin "D36"
		)
		(pin "Y35"
		)
		(pin "C13"
		)
		(pin "F30"
		)
		(pin "L40"
		)
		(pin "M01"
		)
		(pin "F17"
		)
		(pin "Z03"
		)
		(pin "F28"
		)
		(pin "Z40"
		)
		(pin "A39"
		)
		(pin "Y40"
		)
		(pin "M13"
		)
		(pin "M14"
		)
		(pin "M15"
		)
		(pin "D38"
		)
		(pin "Y29"
		)
		(pin "F18"
		)
		(pin "E40"
		)
		(pin "B36"
		)
		(pin "E15"
		)
		(pin "C09"
		)
		(pin "E27"
		)
		(pin "Z31"
		)
		(pin "A06"
		)
		(pin "L22"
		)
		(pin "L23"
		)
		(pin "C34"
		)
		(pin "Y19"
		)
		(pin "J18"
		)
		(pin "J19"
		)
		(pin "L38"
		)
		(pin "L39"
		)
		(pin "G03"
		)
		(pin "F01"
		)
		(pin "M16"
		)
		(pin "M17"
		)
		(pin "M18"
		)
		(pin "J20"
		)
		(pin "J21"
		)
		(pin "H26"
		)
		(pin "H27"
		)
		(pin "Y20"
		)
		(pin "H28"
		)
		(pin "H29"
		)
		(pin "Z34"
		)
		(pin "D26"
		)
		(pin "Y31"
		)
		(pin "G06"
		)
		(pin "Z11"
		)
		(pin "H30"
		)
		(pin "H31"
		)
		(pin "Y04"
		)
		(pin "Z24"
		)
		(pin "D33"
		)
		(pin "F35"
		)
		(pin "B35"
		)
		(pin "B06"
		)
		(pin "B23"
		)
		(pin "M22"
		)
		(pin "M23"
		)
		(pin "M24"
		)
		(pin "Y30"
		)
		(pin "B07"
		)
		(pin "C21"
		)
		(pin "H16"
		)
		(pin "H17"
		)
		(pin "H24"
		)
		(pin "H25"
		)
		(pin "C04"
		)
		(pin "A31"
		)
		(pin "A04"
		)
		(pin "E14"
		)
		(pin "Z38"
		)
		(pin "E17"
		)
		(pin "A21"
		)
		(pin "B03"
		)
		(pin "F04"
		)
		(pin "B13"
		)
		(pin "C14"
		)
		(pin "Z19"
		)
		(pin "Y18"
		)
		(pin "Z14"
		)
		(pin "Z25"
		)
		(pin "J24"
		)
		(pin "J25"
		)
		(pin "H10"
		)
		(pin "H11"
		)
		(pin "K20"
		)
		(pin "K21"
		)
		(pin "F31"
		)
		(pin "F16"
		)
		(pin "E13"
		)
		(pin "F26"
		)
		(pin "C22"
		)
		(pin "E36"
		)
		(pin "J34"
		)
		(pin "J35"
		)
		(pin "C35"
		)
		(pin "L16"
		)
		(pin "L17"
		)
		(pin "J10"
		)
		(pin "J11"
		)
		(pin "L06"
		)
		(pin "L07"
		)
		(pin "D19"
		)
		(pin "Z02"
		)
		(pin "D39"
		)
		(pin "Z32"
		)
		(pin "B25"
		)
		(pin "B05"
		)
		(pin "G30"
		)
		(pin "G31"
		)
		(pin "K02"
		)
		(pin "K03"
		)
		(pin "E03"
		)
		(pin "C38"
		)
		(pin "C17"
		)
		(pin "G02"
		)
		(pin "Y23"
		)
		(pin "D05"
		)
		(pin "L28"
		)
		(pin "L29"
		)
		(pin "Y17"
		)
		(instances
			(project "jetson-agx-thor-baseboard"
				(path ""
					(reference "J18")
					(unit 5)
				)
			)
		)
	)
	(symbol
		(lib_id "antmicropower:+3V3")
		(at 379.73 234.95 0)
		(mirror y)
		(unit 1)
		(exclude_from_sim no)
		(in_bom yes)
		(on_board yes)
		(dnp no)
		(property "Reference" "#PWR0440"
			(at 364.49 234.95 0)
			(effects
				(font
					(size 1.27 1.27)
					(thickness 0.15)
				)
				(justify left bottom)
				(hide yes)
			)
		)
		(property "Value" "+3V3"
			(at 379.984 231.14 0)
			(effects
				(font
					(size 1.27 1.27)
					(thickness 0.15)
				)
			)
		)
		(property "Footprint" ""
			(at 364.49 242.57 0)
			(effects
				(font
					(size 1.27 1.27)
					(thickness 0.15)
				)
				(justify left bottom)
				(hide yes)
			)
		)
		(property "Datasheet" ""
			(at 364.49 245.11 0)
			(effects
				(font
					(size 1.27 1.27)
					(thickness 0.15)
				)
				(justify left bottom)
				(hide yes)
			)
		)
		(property "Description" ""
			(at 379.73 234.95 0)
			(effects
				(font
					(size 1.27 1.27)
				)
				(hide yes)
			)
		)
		(property "Author" "Antmicro"
			(at 364.49 237.49 0)
			(effects
				(font
					(size 1.27 1.27)
					(thickness 0.15)
				)
				(justify left bottom)
				(hide yes)
			)
		)
		(property "License" "Apache-2.0"
			(at 364.49 240.03 0)
			(effects
				(font
					(size 1.27 1.27)
					(thickness 0.15)
				)
				(justify left bottom)
				(hide yes)
			)
		)
		(pin "1"
		)
		(instances
			(project "jetson-agx-thor-baseboard"
				(path ""
					(reference "#PWR0440")
					(unit 1)
				)
			)
		)
	)
	(symbol
		(lib_id "antmicropower:VCC")
		(at 379.73 214.63 0)
		(unit 1)
		(exclude_from_sim no)
		(in_bom yes)
		(on_board yes)
		(dnp no)
		(property "Reference" "#PWR0162"
			(at 379.73 218.44 0)
			(effects
				(font
					(size 1.27 1.27)
				)
				(hide yes)
			)
		)
		(property "Value" "VCC"
			(at 381.762 210.82 0)
			(effects
				(font
					(size 1.27 1.27)
				)
				(justify right)
			)
		)
		(property "Footprint" ""
			(at 379.73 214.63 0)
			(effects
				(font
					(size 1.27 1.27)
				)
				(hide yes)
			)
		)
		(property "Datasheet" ""
			(at 379.73 214.63 0)
			(effects
				(font
					(size 1.27 1.27)
				)
				(hide yes)
			)
		)
		(property "Description" ""
			(at 379.73 214.63 0)
			(effects
				(font
					(size 1.27 1.27)
				)
				(hide yes)
			)
		)
		(pin "1"
		)
		(instances
			(project "jetson-agx-thor-baseboard"
				(path ""
					(reference "#PWR0162")
					(unit 1)
				)
			)
		)
	)
	(symbol
		(lib_id "antmicroB2BConnectors:ASP-208571-01_mounting_holes")
		(at 190.5 29.21 0)
		(mirror y)
		(unit 4)
		(exclude_from_sim no)
		(in_bom yes)
		(on_board yes)
		(dnp no)
		(fields_autoplaced yes)
		(property "Reference" "J18"
			(at 179.07 21.59 0)
			(effects
				(font
					(size 1.27 1.27)
					(thickness 0.15)
				)
			)
		)
		(property "Value" "ASP-208571-01_mounting_holes"
			(at 153.67 39.37 0)
			(effects
				(font
					(size 1.27 1.27)
					(thickness 0.15)
				)
				(justify left bottom)
				(hide yes)
			)
		)
		(property "Footprint" "antmicro-footprints:ASP-208571-01_mounting_holes"
			(at 153.67 41.91 0)
			(effects
				(font
					(size 1.27 1.27)
					(thickness 0.15)
				)
				(justify left bottom)
				(hide yes)
			)
		)
		(property "Datasheet" "https://suddendocs.samtec.com/prints/asp-208571-01-mkt.pdf"
			(at 153.67 44.45 0)
			(effects
				(font
					(size 1.27 1.27)
					(thickness 0.15)
				)
				(justify left bottom)
				(hide yes)
			)
		)
		(property "Description" "FMC connector"
			(at 153.67 54.61 0)
			(effects
				(font
					(size 1.27 1.27)
				)
				(justify left bottom)
				(hide yes)
			)
		)
		(property "MPN" "ASP-208571-01"
			(at 179.07 24.13 0)
			(effects
				(font
					(size 1.27 1.27)
					(thickness 0.15)
				)
			)
		)
		(property "Manufacturer" "Samtec"
			(at 153.67 46.99 0)
			(effects
				(font
					(size 1.27 1.27)
					(thickness 0.15)
				)
				(justify left bottom)
				(hide yes)
			)
		)
		(property "Author" "Antmicro"
			(at 153.67 49.53 0)
			(effects
				(font
					(size 1.27 1.27)
					(thickness 0.15)
				)
				(justify left bottom)
				(hide yes)
			)
		)
		(property "License" "Apache-2.0"
			(at 153.67 52.07 0)
			(effects
				(font
					(size 1.27 1.27)
					(thickness 0.15)
				)
				(justify left bottom)
				(hide yes)
			)
		)
		(pin "A40"
		)
		(pin "Z01"
		)
		(pin "A09"
		)
		(pin "Y28"
		)
		(pin "D27"
		)
		(pin "B33"
		)
		(pin "C25"
		)
		(pin "C20"
		)
		(pin "Z05"
		)
		(pin "A10"
		)
		(pin "B14"
		)
		(pin "Y39"
		)
		(pin "C36"
		)
		(pin "F14"
		)
		(pin "H02"
		)
		(pin "H03"
		)
		(pin "A28"
		)
		(pin "C37"
		)
		(pin "A26"
		)
		(pin "C19"
		)
		(pin "Z06"
		)
		(pin "C28"
		)
		(pin "B10"
		)
		(pin "Z27"
		)
		(pin "B40"
		)
		(pin "Z28"
		)
		(pin "Z26"
		)
		(pin "C24"
		)
		(pin "B09"
		)
		(pin "Y27"
		)
		(pin "C08"
		)
		(pin "Z04"
		)
		(pin "A36"
		)
		(pin "C02"
		)
		(pin "A19"
		)
		(pin "E34"
		)
		(pin "K28"
		)
		(pin "K29"
		)
		(pin "G20"
		)
		(pin "G21"
		)
		(pin "A08"
		)
		(pin "B27"
		)
		(pin "D22"
		)
		(pin "F25"
		)
		(pin "C30"
		)
		(pin "D04"
		)
		(pin "A30"
		)
		(pin "A38"
		)
		(pin "B37"
		)
		(pin "G26"
		)
		(pin "G27"
		)
		(pin "C03"
		)
		(pin "F07"
		)
		(pin "D34"
		)
		(pin "G08"
		)
		(pin "G18"
		)
		(pin "G19"
		)
		(pin "G01"
		)
		(pin "A20"
		)
		(pin "M04"
		)
		(pin "M05"
		)
		(pin "Y08"
		)
		(pin "F39"
		)
		(pin "F19"
		)
		(pin "K04"
		)
		(pin "K05"
		)
		(pin "G12"
		)
		(pin "G13"
		)
		(pin "Y02"
		)
		(pin "J32"
		)
		(pin "J33"
		)
		(pin "B11"
		)
		(pin "D07"
		)
		(pin "C33"
		)
		(pin "A17"
		)
		(pin "D14"
		)
		(pin "A15"
		)
		(pin "B39"
		)
		(pin "A18"
		)
		(pin "B21"
		)
		(pin "D11"
		)
		(pin "Y15"
		)
		(pin "B16"
		)
		(pin "Y09"
		)
		(pin "F29"
		)
		(pin "J30"
		)
		(pin "J31"
		)
		(pin "B19"
		)
		(pin "A05"
		)
		(pin "B38"
		)
		(pin "E22"
		)
		(pin "D15"
		)
		(pin "L02"
		)
		(pin "L03"
		)
		(pin "Y37"
		)
		(pin "E07"
		)
		(pin "A22"
		)
		(pin "H20"
		)
		(pin "H21"
		)
		(pin "Z39"
		)
		(pin "F37"
		)
		(pin "B30"
		)
		(pin "Z15"
		)
		(pin "H36"
		)
		(pin "H37"
		)
		(pin "D16"
		)
		(pin "D37"
		)
		(pin "C40"
		)
		(pin "E29"
		)
		(pin "Y36"
		)
		(pin "K10"
		)
		(pin "K11"
		)
		(pin "F38"
		)
		(pin "B04"
		)
		(pin "F15"
		)
		(pin "J28"
		)
		(pin "J29"
		)
		(pin "B17"
		)
		(pin "E37"
		)
		(pin "E09"
		)
		(pin "Z23"
		)
		(pin "J06"
		)
		(pin "J07"
		)
		(pin "Z30"
		)
		(pin "C31"
		)
		(pin "Z37"
		)
		(pin "Z33"
		)
		(pin "Z29"
		)
		(pin "Y26"
		)
		(pin "H06"
		)
		(pin "H07"
		)
		(pin "C10"
		)
		(pin "F27"
		)
		(pin "A03"
		)
		(pin "M10"
		)
		(pin "M11"
		)
		(pin "M12"
		)
		(pin "L04"
		)
		(pin "L05"
		)
		(pin "A24"
		)
		(pin "M28"
		)
		(pin "M29"
		)
		(pin "M30"
		)
		(pin "D32"
		)
		(pin "H18"
		)
		(pin "H19"
		)
		(pin "F03"
		)
		(pin "L08"
		)
		(pin "L09"
		)
		(pin "A01"
		)
		(pin "B32"
		)
		(pin "K36"
		)
		(pin "K37"
		)
		(pin "C01"
		)
		(pin "D18"
		)
		(pin "E12"
		)
		(pin "K16"
		)
		(pin "K17"
		)
		(pin "Y11"
		)
		(pin "B31"
		)
		(pin "D28"
		)
		(pin "D23"
		)
		(pin "Z18"
		)
		(pin "D17"
		)
		(pin "F32"
		)
		(pin "B20"
		)
		(pin "C18"
		)
		(pin "A25"
		)
		(pin "Y05"
		)
		(pin "J26"
		)
		(pin "J27"
		)
		(pin "Y33"
		)
		(pin "A37"
		)
		(pin "Z21"
		)
		(pin "D09"
		)
		(pin "B26"
		)
		(pin "A35"
		)
		(pin "D20"
		)
		(pin "A11"
		)
		(pin "C15"
		)
		(pin "G14"
		)
		(pin "G15"
		)
		(pin "D01"
		)
		(pin "D21"
		)
		(pin "M34"
		)
		(pin "M35"
		)
		(pin "M36"
		)
		(pin "L32"
		)
		(pin "L33"
		)
		(pin "D31"
		)
		(pin "Z07"
		)
		(pin "M31"
		)
		(pin "M32"
		)
		(pin "M33"
		)
		(pin "K18"
		)
		(pin "K19"
		)
		(pin "F06"
		)
		(pin "Z16"
		)
		(pin "H32"
		)
		(pin "H33"
		)
		(pin "Z36"
		)
		(pin "F05"
		)
		(pin "F02"
		)
		(pin "E05"
		)
		(pin "F40"
		)
		(pin "E39"
		)
		(pin "H08"
		)
		(pin "H09"
		)
		(pin "B02"
		)
		(pin "E16"
		)
		(pin "E38"
		)
		(pin "Z12"
		)
		(pin "A34"
		)
		(pin "K08"
		)
		(pin "K09"
		)
		(pin "E31"
		)
		(pin "Y06"
		)
		(pin "F11"
		)
		(pin "F08"
		)
		(pin "A32"
		)
		(pin "Y22"
		)
		(pin "H12"
		)
		(pin "H13"
		)
		(pin "A27"
		)
		(pin "C05"
		)
		(pin "K12"
		)
		(pin "K13"
		)
		(pin "L14"
		)
		(pin "L15"
		)
		(pin "E25"
		)
		(pin "L18"
		)
		(pin "L19"
		)
		(pin "M19"
		)
		(pin "M20"
		)
		(pin "M21"
		)
		(pin "J14"
		)
		(pin "J15"
		)
		(pin "G40"
		)
		(pin "H01"
		)
		(pin "Y25"
		)
		(pin "A33"
		)
		(pin "Z35"
		)
		(pin "H38"
		)
		(pin "H39"
		)
		(pin "D29"
		)
		(pin "E02"
		)
		(pin "D10"
		)
		(pin "C12"
		)
		(pin "C26"
		)
		(pin "M40"
		)
		(pin "B24"
		)
		(pin "Y24"
		)
		(pin "F33"
		)
		(pin "F21"
		)
		(pin "E20"
		)
		(pin "D06"
		)
		(pin "C29"
		)
		(pin "E23"
		)
		(pin "J04"
		)
		(pin "J05"
		)
		(pin "B28"
		)
		(pin "K30"
		)
		(pin "K31"
		)
		(pin "B08"
		)
		(pin "L12"
		)
		(pin "L13"
		)
		(pin "J38"
		)
		(pin "J39"
		)
		(pin "D24"
		)
		(pin "E06"
		)
		(pin "D35"
		)
		(pin "G07"
		)
		(pin "C39"
		)
		(pin "E04"
		)
		(pin "L34"
		)
		(pin "L35"
		)
		(pin "D02"
		)
		(pin "Z22"
		)
		(pin "K14"
		)
		(pin "K15"
		)
		(pin "Y34"
		)
		(pin "M08"
		)
		(pin "M09"
		)
		(pin "D30"
		)
		(pin "G10"
		)
		(pin "G11"
		)
		(pin "C11"
		)
		(pin "E33"
		)
		(pin "G38"
		)
		(pin "G39"
		)
		(pin "F34"
		)
		(pin "H04"
		)
		(pin "H05"
		)
		(pin "F09"
		)
		(pin "G22"
		)
		(pin "G23"
		)
		(pin "B34"
		)
		(pin "Z20"
		)
		(pin "Y03"
		)
		(pin "M06"
		)
		(pin "M07"
		)
		(pin "K38"
		)
		(pin "K39"
		)
		(pin "Y21"
		)
		(pin "K24"
		)
		(pin "K25"
		)
		(pin "E21"
		)
		(pin "L20"
		)
		(pin "L21"
		)
		(pin "E11"
		)
		(pin "K22"
		)
		(pin "K23"
		)
		(pin "B12"
		)
		(pin "J22"
		)
		(pin "J23"
		)
		(pin "A07"
		)
		(pin "E32"
		)
		(pin "L36"
		)
		(pin "L37"
		)
		(pin "L24"
		)
		(pin "L25"
		)
		(pin "Y32"
		)
		(pin "F13"
		)
		(pin "G09"
		)
		(pin "Y01"
		)
		(pin "K06"
		)
		(pin "K07"
		)
		(pin "G28"
		)
		(pin "G29"
		)
		(pin "K40"
		)
		(pin "L01"
		)
		(pin "J02"
		)
		(pin "J03"
		)
		(pin "J12"
		)
		(pin "J13"
		)
		(pin "M25"
		)
		(pin "M26"
		)
		(pin "M27"
		)
		(pin "A13"
		)
		(pin "F20"
		)
		(pin "M37"
		)
		(pin "M38"
		)
		(pin "M39"
		)
		(pin "Y10"
		)
		(pin "G32"
		)
		(pin "G33"
		)
		(pin "A29"
		)
		(pin "L10"
		)
		(pin "L11"
		)
		(pin "G24"
		)
		(pin "G25"
		)
		(pin "E08"
		)
		(pin "C06"
		)
		(pin "A12"
		)
		(pin "F12"
		)
		(pin "C16"
		)
		(pin "Z09"
		)
		(pin "E19"
		)
		(pin "D03"
		)
		(pin "E24"
		)
		(pin "F23"
		)
		(pin "G16"
		)
		(pin "G17"
		)
		(pin "A23"
		)
		(pin "D12"
		)
		(pin "C07"
		)
		(pin "L30"
		)
		(pin "L31"
		)
		(pin "B29"
		)
		(pin "B15"
		)
		(pin "J16"
		)
		(pin "J17"
		)
		(pin "K26"
		)
		(pin "K27"
		)
		(pin "A16"
		)
		(pin "E01"
		)
		(pin "Y12"
		)
		(pin "G04"
		)
		(pin "C32"
		)
		(pin "B22"
		)
		(pin "Y16"
		)
		(pin "G34"
		)
		(pin "G35"
		)
		(pin "A02"
		)
		(pin "D40"
		)
		(pin "Y38"
		)
		(pin "D08"
		)
		(pin "C27"
		)
		(pin "J36"
		)
		(pin "J37"
		)
		(pin "K34"
		)
		(pin "K35"
		)
		(pin "M02"
		)
		(pin "M03"
		)
		(pin "B01"
		)
		(pin "E35"
		)
		(pin "Y13"
		)
		(pin "L26"
		)
		(pin "L27"
		)
		(pin "G36"
		)
		(pin "G37"
		)
		(pin "K32"
		)
		(pin "K33"
		)
		(pin "Y14"
		)
		(pin "D13"
		)
		(pin "D25"
		)
		(pin "F10"
		)
		(pin "E10"
		)
		(pin "E26"
		)
		(pin "E18"
		)
		(pin "F24"
		)
		(pin "Z10"
		)
		(pin "H40"
		)
		(pin "J01"
		)
		(pin "G05"
		)
		(pin "Z17"
		)
		(pin "F22"
		)
		(pin "A14"
		)
		(pin "E30"
		)
		(pin "Z13"
		)
		(pin "H22"
		)
		(pin "H23"
		)
		(pin "E28"
		)
		(pin "F36"
		)
		(pin "B18"
		)
		(pin "Z08"
		)
		(pin "H34"
		)
		(pin "H35"
		)
		(pin "J08"
		)
		(pin "J09"
		)
		(pin "C23"
		)
		(pin "J40"
		)
		(pin "K01"
		)
		(pin "Y07"
		)
		(pin "H14"
		)
		(pin "H15"
		)
		(pin "D36"
		)
		(pin "Y35"
		)
		(pin "C13"
		)
		(pin "F30"
		)
		(pin "L40"
		)
		(pin "M01"
		)
		(pin "F17"
		)
		(pin "Z03"
		)
		(pin "F28"
		)
		(pin "Z40"
		)
		(pin "A39"
		)
		(pin "Y40"
		)
		(pin "M13"
		)
		(pin "M14"
		)
		(pin "M15"
		)
		(pin "D38"
		)
		(pin "Y29"
		)
		(pin "F18"
		)
		(pin "E40"
		)
		(pin "B36"
		)
		(pin "E15"
		)
		(pin "C09"
		)
		(pin "E27"
		)
		(pin "Z31"
		)
		(pin "A06"
		)
		(pin "L22"
		)
		(pin "L23"
		)
		(pin "C34"
		)
		(pin "Y19"
		)
		(pin "J18"
		)
		(pin "J19"
		)
		(pin "L38"
		)
		(pin "L39"
		)
		(pin "G03"
		)
		(pin "F01"
		)
		(pin "M16"
		)
		(pin "M17"
		)
		(pin "M18"
		)
		(pin "J20"
		)
		(pin "J21"
		)
		(pin "H26"
		)
		(pin "H27"
		)
		(pin "Y20"
		)
		(pin "H28"
		)
		(pin "H29"
		)
		(pin "Z34"
		)
		(pin "D26"
		)
		(pin "Y31"
		)
		(pin "G06"
		)
		(pin "Z11"
		)
		(pin "H30"
		)
		(pin "H31"
		)
		(pin "Y04"
		)
		(pin "Z24"
		)
		(pin "D33"
		)
		(pin "F35"
		)
		(pin "B35"
		)
		(pin "B06"
		)
		(pin "B23"
		)
		(pin "M22"
		)
		(pin "M23"
		)
		(pin "M24"
		)
		(pin "Y30"
		)
		(pin "B07"
		)
		(pin "C21"
		)
		(pin "H16"
		)
		(pin "H17"
		)
		(pin "H24"
		)
		(pin "H25"
		)
		(pin "C04"
		)
		(pin "A31"
		)
		(pin "A04"
		)
		(pin "E14"
		)
		(pin "Z38"
		)
		(pin "E17"
		)
		(pin "A21"
		)
		(pin "B03"
		)
		(pin "F04"
		)
		(pin "B13"
		)
		(pin "C14"
		)
		(pin "Z19"
		)
		(pin "Y18"
		)
		(pin "Z14"
		)
		(pin "Z25"
		)
		(pin "J24"
		)
		(pin "J25"
		)
		(pin "H10"
		)
		(pin "H11"
		)
		(pin "K20"
		)
		(pin "K21"
		)
		(pin "F31"
		)
		(pin "F16"
		)
		(pin "E13"
		)
		(pin "F26"
		)
		(pin "C22"
		)
		(pin "E36"
		)
		(pin "J34"
		)
		(pin "J35"
		)
		(pin "C35"
		)
		(pin "L16"
		)
		(pin "L17"
		)
		(pin "J10"
		)
		(pin "J11"
		)
		(pin "L06"
		)
		(pin "L07"
		)
		(pin "D19"
		)
		(pin "Z02"
		)
		(pin "D39"
		)
		(pin "Z32"
		)
		(pin "B25"
		)
		(pin "B05"
		)
		(pin "G30"
		)
		(pin "G31"
		)
		(pin "K02"
		)
		(pin "K03"
		)
		(pin "E03"
		)
		(pin "C38"
		)
		(pin "C17"
		)
		(pin "G02"
		)
		(pin "Y23"
		)
		(pin "D05"
		)
		(pin "L28"
		)
		(pin "L29"
		)
		(pin "Y17"
		)
		(instances
			(project "jetson-agx-thor-baseboard"
				(path ""
					(reference "J18")
					(unit 4)
				)
			)
		)
	)
	(symbol
		(lib_id "antmicroResistors0402:R_10k_0402")
		(at 72.39 30.48 270)
		(mirror x)
		(unit 1)
		(exclude_from_sim no)
		(in_bom yes)
		(on_board yes)
		(dnp no)
		(fields_autoplaced yes)
		(property "Reference" "R349"
			(at 69.85 26.67 90)
			(effects
				(font
					(size 1.27 1.27)
					(thickness 0.15)
				)
				(justify right)
			)
		)
		(property "Value" "R_10k_0402"
			(at 59.69 10.16 0)
			(effects
				(font
					(size 1.27 1.27)
					(thickness 0.15)
				)
				(justify left bottom)
				(hide yes)
			)
		)
		(property "Footprint" "antmicro-footprints:R_0402_1005Metric"
			(at 57.15 10.16 0)
			(effects
				(font
					(size 1.27 1.27)
					(thickness 0.15)
				)
				(justify left bottom)
				(hide yes)
			)
		)
		(property "Datasheet" "https://www.bourns.com/docs/product-datasheets/cr.pdf"
			(at 54.61 10.16 0)
			(effects
				(font
					(size 1.27 1.27)
					(thickness 0.15)
				)
				(justify left bottom)
				(hide yes)
			)
		)
		(property "Description" "SMD Chip Resistor, 10 kohm, ± 1%, 62.5 mW, 0402 [1005 Metric], Thick Film, General Purpose"
			(at 41.91 10.16 0)
			(effects
				(font
					(size 1.27 1.27)
				)
				(justify left bottom)
				(hide yes)
			)
		)
		(property "MPN" "CR0402-FX-1002GLF"
			(at 52.07 10.16 0)
			(effects
				(font
					(size 1.27 1.27)
					(thickness 0.15)
				)
				(justify left bottom)
				(hide yes)
			)
		)
		(property "Manufacturer" "Bourns"
			(at 49.53 10.16 0)
			(effects
				(font
					(size 1.27 1.27)
					(thickness 0.15)
				)
				(justify left bottom)
				(hide yes)
			)
		)
		(property "License" "Apache-2.0"
			(at 46.99 10.16 0)
			(effects
				(font
					(size 1.27 1.27)
					(thickness 0.15)
				)
				(justify left bottom)
				(hide yes)
			)
		)
		(property "Author" "Antmicro"
			(at 44.45 10.16 0)
			(effects
				(font
					(size 1.27 1.27)
					(thickness 0.15)
				)
				(justify left bottom)
				(hide yes)
			)
		)
		(property "Val" "10k"
			(at 69.85 29.21 90)
			(effects
				(font
					(size 1.27 1.27)
					(thickness 0.15)
				)
				(justify right)
			)
		)
		(property "Tolerance" "1%"
			(at 62.23 10.16 0)
			(effects
				(font
					(size 1.27 1.27)
				)
				(justify left bottom)
				(hide yes)
			)
		)
		(pin "1"
		)
		(pin "2"
		)
		(instances
			(project ""
				(path ""
					(reference "R349")
					(unit 1)
				)
			)
		)
	)
	(symbol
		(lib_id "antmicroB2BConnectors:ASP-208571-01_mounting_holes")
		(at 143.51 153.67 0)
		(mirror y)
		(unit 6)
		(exclude_from_sim no)
		(in_bom yes)
		(on_board yes)
		(dnp no)
		(fields_autoplaced yes)
		(property "Reference" "J18"
			(at 132.08 146.05 0)
			(effects
				(font
					(size 1.27 1.27)
					(thickness 0.15)
				)
			)
		)
		(property "Value" "ASP-208571-01_mounting_holes"
			(at 106.68 163.83 0)
			(effects
				(font
					(size 1.27 1.27)
					(thickness 0.15)
				)
				(justify left bottom)
				(hide yes)
			)
		)
		(property "Footprint" "antmicro-footprints:ASP-208571-01_mounting_holes"
			(at 106.68 166.37 0)
			(effects
				(font
					(size 1.27 1.27)
					(thickness 0.15)
				)
				(justify left bottom)
				(hide yes)
			)
		)
		(property "Datasheet" "https://suddendocs.samtec.com/prints/asp-208571-01-mkt.pdf"
			(at 106.68 168.91 0)
			(effects
				(font
					(size 1.27 1.27)
					(thickness 0.15)
				)
				(justify left bottom)
				(hide yes)
			)
		)
		(property "Description" "FMC connector"
			(at 106.68 179.07 0)
			(effects
				(font
					(size 1.27 1.27)
				)
				(justify left bottom)
				(hide yes)
			)
		)
		(property "MPN" "ASP-208571-01"
			(at 132.08 148.59 0)
			(effects
				(font
					(size 1.27 1.27)
					(thickness 0.15)
				)
			)
		)
		(property "Manufacturer" "Samtec"
			(at 106.68 171.45 0)
			(effects
				(font
					(size 1.27 1.27)
					(thickness 0.15)
				)
				(justify left bottom)
				(hide yes)
			)
		)
		(property "Author" "Antmicro"
			(at 106.68 173.99 0)
			(effects
				(font
					(size 1.27 1.27)
					(thickness 0.15)
				)
				(justify left bottom)
				(hide yes)
			)
		)
		(property "License" "Apache-2.0"
			(at 106.68 176.53 0)
			(effects
				(font
					(size 1.27 1.27)
					(thickness 0.15)
				)
				(justify left bottom)
				(hide yes)
			)
		)
		(pin "A40"
		)
		(pin "Z01"
		)
		(pin "A09"
		)
		(pin "Y28"
		)
		(pin "D27"
		)
		(pin "B33"
		)
		(pin "C25"
		)
		(pin "C20"
		)
		(pin "Z05"
		)
		(pin "A10"
		)
		(pin "B14"
		)
		(pin "Y39"
		)
		(pin "C36"
		)
		(pin "F14"
		)
		(pin "H02"
		)
		(pin "H03"
		)
		(pin "A28"
		)
		(pin "C37"
		)
		(pin "A26"
		)
		(pin "C19"
		)
		(pin "Z06"
		)
		(pin "C28"
		)
		(pin "B10"
		)
		(pin "Z27"
		)
		(pin "B40"
		)
		(pin "Z28"
		)
		(pin "Z26"
		)
		(pin "C24"
		)
		(pin "B09"
		)
		(pin "Y27"
		)
		(pin "C08"
		)
		(pin "Z04"
		)
		(pin "A36"
		)
		(pin "C02"
		)
		(pin "A19"
		)
		(pin "E34"
		)
		(pin "K28"
		)
		(pin "K29"
		)
		(pin "G20"
		)
		(pin "G21"
		)
		(pin "A08"
		)
		(pin "B27"
		)
		(pin "D22"
		)
		(pin "F25"
		)
		(pin "C30"
		)
		(pin "D04"
		)
		(pin "A30"
		)
		(pin "A38"
		)
		(pin "B37"
		)
		(pin "G26"
		)
		(pin "G27"
		)
		(pin "C03"
		)
		(pin "F07"
		)
		(pin "D34"
		)
		(pin "G08"
		)
		(pin "G18"
		)
		(pin "G19"
		)
		(pin "G01"
		)
		(pin "A20"
		)
		(pin "M04"
		)
		(pin "M05"
		)
		(pin "Y08"
		)
		(pin "F39"
		)
		(pin "F19"
		)
		(pin "K04"
		)
		(pin "K05"
		)
		(pin "G12"
		)
		(pin "G13"
		)
		(pin "Y02"
		)
		(pin "J32"
		)
		(pin "J33"
		)
		(pin "B11"
		)
		(pin "D07"
		)
		(pin "C33"
		)
		(pin "A17"
		)
		(pin "D14"
		)
		(pin "A15"
		)
		(pin "B39"
		)
		(pin "A18"
		)
		(pin "B21"
		)
		(pin "D11"
		)
		(pin "Y15"
		)
		(pin "B16"
		)
		(pin "Y09"
		)
		(pin "F29"
		)
		(pin "J30"
		)
		(pin "J31"
		)
		(pin "B19"
		)
		(pin "A05"
		)
		(pin "B38"
		)
		(pin "E22"
		)
		(pin "D15"
		)
		(pin "L02"
		)
		(pin "L03"
		)
		(pin "Y37"
		)
		(pin "E07"
		)
		(pin "A22"
		)
		(pin "H20"
		)
		(pin "H21"
		)
		(pin "Z39"
		)
		(pin "F37"
		)
		(pin "B30"
		)
		(pin "Z15"
		)
		(pin "H36"
		)
		(pin "H37"
		)
		(pin "D16"
		)
		(pin "D37"
		)
		(pin "C40"
		)
		(pin "E29"
		)
		(pin "Y36"
		)
		(pin "K10"
		)
		(pin "K11"
		)
		(pin "F38"
		)
		(pin "B04"
		)
		(pin "F15"
		)
		(pin "J28"
		)
		(pin "J29"
		)
		(pin "B17"
		)
		(pin "E37"
		)
		(pin "E09"
		)
		(pin "Z23"
		)
		(pin "J06"
		)
		(pin "J07"
		)
		(pin "Z30"
		)
		(pin "C31"
		)
		(pin "Z37"
		)
		(pin "Z33"
		)
		(pin "Z29"
		)
		(pin "Y26"
		)
		(pin "H06"
		)
		(pin "H07"
		)
		(pin "C10"
		)
		(pin "F27"
		)
		(pin "A03"
		)
		(pin "M10"
		)
		(pin "M11"
		)
		(pin "M12"
		)
		(pin "L04"
		)
		(pin "L05"
		)
		(pin "A24"
		)
		(pin "M28"
		)
		(pin "M29"
		)
		(pin "M30"
		)
		(pin "D32"
		)
		(pin "H18"
		)
		(pin "H19"
		)
		(pin "F03"
		)
		(pin "L08"
		)
		(pin "L09"
		)
		(pin "A01"
		)
		(pin "B32"
		)
		(pin "K36"
		)
		(pin "K37"
		)
		(pin "C01"
		)
		(pin "D18"
		)
		(pin "E12"
		)
		(pin "K16"
		)
		(pin "K17"
		)
		(pin "Y11"
		)
		(pin "B31"
		)
		(pin "D28"
		)
		(pin "D23"
		)
		(pin "Z18"
		)
		(pin "D17"
		)
		(pin "F32"
		)
		(pin "B20"
		)
		(pin "C18"
		)
		(pin "A25"
		)
		(pin "Y05"
		)
		(pin "J26"
		)
		(pin "J27"
		)
		(pin "Y33"
		)
		(pin "A37"
		)
		(pin "Z21"
		)
		(pin "D09"
		)
		(pin "B26"
		)
		(pin "A35"
		)
		(pin "D20"
		)
		(pin "A11"
		)
		(pin "C15"
		)
		(pin "G14"
		)
		(pin "G15"
		)
		(pin "D01"
		)
		(pin "D21"
		)
		(pin "M34"
		)
		(pin "M35"
		)
		(pin "M36"
		)
		(pin "L32"
		)
		(pin "L33"
		)
		(pin "D31"
		)
		(pin "Z07"
		)
		(pin "M31"
		)
		(pin "M32"
		)
		(pin "M33"
		)
		(pin "K18"
		)
		(pin "K19"
		)
		(pin "F06"
		)
		(pin "Z16"
		)
		(pin "H32"
		)
		(pin "H33"
		)
		(pin "Z36"
		)
		(pin "F05"
		)
		(pin "F02"
		)
		(pin "E05"
		)
		(pin "F40"
		)
		(pin "E39"
		)
		(pin "H08"
		)
		(pin "H09"
		)
		(pin "B02"
		)
		(pin "E16"
		)
		(pin "E38"
		)
		(pin "Z12"
		)
		(pin "A34"
		)
		(pin "K08"
		)
		(pin "K09"
		)
		(pin "E31"
		)
		(pin "Y06"
		)
		(pin "F11"
		)
		(pin "F08"
		)
		(pin "A32"
		)
		(pin "Y22"
		)
		(pin "H12"
		)
		(pin "H13"
		)
		(pin "A27"
		)
		(pin "C05"
		)
		(pin "K12"
		)
		(pin "K13"
		)
		(pin "L14"
		)
		(pin "L15"
		)
		(pin "E25"
		)
		(pin "L18"
		)
		(pin "L19"
		)
		(pin "M19"
		)
		(pin "M20"
		)
		(pin "M21"
		)
		(pin "J14"
		)
		(pin "J15"
		)
		(pin "G40"
		)
		(pin "H01"
		)
		(pin "Y25"
		)
		(pin "A33"
		)
		(pin "Z35"
		)
		(pin "H38"
		)
		(pin "H39"
		)
		(pin "D29"
		)
		(pin "E02"
		)
		(pin "D10"
		)
		(pin "C12"
		)
		(pin "C26"
		)
		(pin "M40"
		)
		(pin "B24"
		)
		(pin "Y24"
		)
		(pin "F33"
		)
		(pin "F21"
		)
		(pin "E20"
		)
		(pin "D06"
		)
		(pin "C29"
		)
		(pin "E23"
		)
		(pin "J04"
		)
		(pin "J05"
		)
		(pin "B28"
		)
		(pin "K30"
		)
		(pin "K31"
		)
		(pin "B08"
		)
		(pin "L12"
		)
		(pin "L13"
		)
		(pin "J38"
		)
		(pin "J39"
		)
		(pin "D24"
		)
		(pin "E06"
		)
		(pin "D35"
		)
		(pin "G07"
		)
		(pin "C39"
		)
		(pin "E04"
		)
		(pin "L34"
		)
		(pin "L35"
		)
		(pin "D02"
		)
		(pin "Z22"
		)
		(pin "K14"
		)
		(pin "K15"
		)
		(pin "Y34"
		)
		(pin "M08"
		)
		(pin "M09"
		)
		(pin "D30"
		)
		(pin "G10"
		)
		(pin "G11"
		)
		(pin "C11"
		)
		(pin "E33"
		)
		(pin "G38"
		)
		(pin "G39"
		)
		(pin "F34"
		)
		(pin "H04"
		)
		(pin "H05"
		)
		(pin "F09"
		)
		(pin "G22"
		)
		(pin "G23"
		)
		(pin "B34"
		)
		(pin "Z20"
		)
		(pin "Y03"
		)
		(pin "M06"
		)
		(pin "M07"
		)
		(pin "K38"
		)
		(pin "K39"
		)
		(pin "Y21"
		)
		(pin "K24"
		)
		(pin "K25"
		)
		(pin "E21"
		)
		(pin "L20"
		)
		(pin "L21"
		)
		(pin "E11"
		)
		(pin "K22"
		)
		(pin "K23"
		)
		(pin "B12"
		)
		(pin "J22"
		)
		(pin "J23"
		)
		(pin "A07"
		)
		(pin "E32"
		)
		(pin "L36"
		)
		(pin "L37"
		)
		(pin "L24"
		)
		(pin "L25"
		)
		(pin "Y32"
		)
		(pin "F13"
		)
		(pin "G09"
		)
		(pin "Y01"
		)
		(pin "K06"
		)
		(pin "K07"
		)
		(pin "G28"
		)
		(pin "G29"
		)
		(pin "K40"
		)
		(pin "L01"
		)
		(pin "J02"
		)
		(pin "J03"
		)
		(pin "J12"
		)
		(pin "J13"
		)
		(pin "M25"
		)
		(pin "M26"
		)
		(pin "M27"
		)
		(pin "A13"
		)
		(pin "F20"
		)
		(pin "M37"
		)
		(pin "M38"
		)
		(pin "M39"
		)
		(pin "Y10"
		)
		(pin "G32"
		)
		(pin "G33"
		)
		(pin "A29"
		)
		(pin "L10"
		)
		(pin "L11"
		)
		(pin "G24"
		)
		(pin "G25"
		)
		(pin "E08"
		)
		(pin "C06"
		)
		(pin "A12"
		)
		(pin "F12"
		)
		(pin "C16"
		)
		(pin "Z09"
		)
		(pin "E19"
		)
		(pin "D03"
		)
		(pin "E24"
		)
		(pin "F23"
		)
		(pin "G16"
		)
		(pin "G17"
		)
		(pin "A23"
		)
		(pin "D12"
		)
		(pin "C07"
		)
		(pin "L30"
		)
		(pin "L31"
		)
		(pin "B29"
		)
		(pin "B15"
		)
		(pin "J16"
		)
		(pin "J17"
		)
		(pin "K26"
		)
		(pin "K27"
		)
		(pin "A16"
		)
		(pin "E01"
		)
		(pin "Y12"
		)
		(pin "G04"
		)
		(pin "C32"
		)
		(pin "B22"
		)
		(pin "Y16"
		)
		(pin "G34"
		)
		(pin "G35"
		)
		(pin "A02"
		)
		(pin "D40"
		)
		(pin "Y38"
		)
		(pin "D08"
		)
		(pin "C27"
		)
		(pin "J36"
		)
		(pin "J37"
		)
		(pin "K34"
		)
		(pin "K35"
		)
		(pin "M02"
		)
		(pin "M03"
		)
		(pin "B01"
		)
		(pin "E35"
		)
		(pin "Y13"
		)
		(pin "L26"
		)
		(pin "L27"
		)
		(pin "G36"
		)
		(pin "G37"
		)
		(pin "K32"
		)
		(pin "K33"
		)
		(pin "Y14"
		)
		(pin "D13"
		)
		(pin "D25"
		)
		(pin "F10"
		)
		(pin "E10"
		)
		(pin "E26"
		)
		(pin "E18"
		)
		(pin "F24"
		)
		(pin "Z10"
		)
		(pin "H40"
		)
		(pin "J01"
		)
		(pin "G05"
		)
		(pin "Z17"
		)
		(pin "F22"
		)
		(pin "A14"
		)
		(pin "E30"
		)
		(pin "Z13"
		)
		(pin "H22"
		)
		(pin "H23"
		)
		(pin "E28"
		)
		(pin "F36"
		)
		(pin "B18"
		)
		(pin "Z08"
		)
		(pin "H34"
		)
		(pin "H35"
		)
		(pin "J08"
		)
		(pin "J09"
		)
		(pin "C23"
		)
		(pin "J40"
		)
		(pin "K01"
		)
		(pin "Y07"
		)
		(pin "H14"
		)
		(pin "H15"
		)
		(pin "D36"
		)
		(pin "Y35"
		)
		(pin "C13"
		)
		(pin "F30"
		)
		(pin "L40"
		)
		(pin "M01"
		)
		(pin "F17"
		)
		(pin "Z03"
		)
		(pin "F28"
		)
		(pin "Z40"
		)
		(pin "A39"
		)
		(pin "Y40"
		)
		(pin "M13"
		)
		(pin "M14"
		)
		(pin "M15"
		)
		(pin "D38"
		)
		(pin "Y29"
		)
		(pin "F18"
		)
		(pin "E40"
		)
		(pin "B36"
		)
		(pin "E15"
		)
		(pin "C09"
		)
		(pin "E27"
		)
		(pin "Z31"
		)
		(pin "A06"
		)
		(pin "L22"
		)
		(pin "L23"
		)
		(pin "C34"
		)
		(pin "Y19"
		)
		(pin "J18"
		)
		(pin "J19"
		)
		(pin "L38"
		)
		(pin "L39"
		)
		(pin "G03"
		)
		(pin "F01"
		)
		(pin "M16"
		)
		(pin "M17"
		)
		(pin "M18"
		)
		(pin "J20"
		)
		(pin "J21"
		)
		(pin "H26"
		)
		(pin "H27"
		)
		(pin "Y20"
		)
		(pin "H28"
		)
		(pin "H29"
		)
		(pin "Z34"
		)
		(pin "D26"
		)
		(pin "Y31"
		)
		(pin "G06"
		)
		(pin "Z11"
		)
		(pin "H30"
		)
		(pin "H31"
		)
		(pin "Y04"
		)
		(pin "Z24"
		)
		(pin "D33"
		)
		(pin "F35"
		)
		(pin "B35"
		)
		(pin "B06"
		)
		(pin "B23"
		)
		(pin "M22"
		)
		(pin "M23"
		)
		(pin "M24"
		)
		(pin "Y30"
		)
		(pin "B07"
		)
		(pin "C21"
		)
		(pin "H16"
		)
		(pin "H17"
		)
		(pin "H24"
		)
		(pin "H25"
		)
		(pin "C04"
		)
		(pin "A31"
		)
		(pin "A04"
		)
		(pin "E14"
		)
		(pin "Z38"
		)
		(pin "E17"
		)
		(pin "A21"
		)
		(pin "B03"
		)
		(pin "F04"
		)
		(pin "B13"
		)
		(pin "C14"
		)
		(pin "Z19"
		)
		(pin "Y18"
		)
		(pin "Z14"
		)
		(pin "Z25"
		)
		(pin "J24"
		)
		(pin "J25"
		)
		(pin "H10"
		)
		(pin "H11"
		)
		(pin "K20"
		)
		(pin "K21"
		)
		(pin "F31"
		)
		(pin "F16"
		)
		(pin "E13"
		)
		(pin "F26"
		)
		(pin "C22"
		)
		(pin "E36"
		)
		(pin "J34"
		)
		(pin "J35"
		)
		(pin "C35"
		)
		(pin "L16"
		)
		(pin "L17"
		)
		(pin "J10"
		)
		(pin "J11"
		)
		(pin "L06"
		)
		(pin "L07"
		)
		(pin "D19"
		)
		(pin "Z02"
		)
		(pin "D39"
		)
		(pin "Z32"
		)
		(pin "B25"
		)
		(pin "B05"
		)
		(pin "G30"
		)
		(pin "G31"
		)
		(pin "K02"
		)
		(pin "K03"
		)
		(pin "E03"
		)
		(pin "C38"
		)
		(pin "C17"
		)
		(pin "G02"
		)
		(pin "Y23"
		)
		(pin "D05"
		)
		(pin "L28"
		)
		(pin "L29"
		)
		(pin "Y17"
		)
		(instances
			(project "jetson-agx-thor-baseboard"
				(path ""
					(reference "J18")
					(unit 6)
				)
			)
		)
	)
	(symbol
		(lib_id "antmicropower:GND")
		(at 328.93 129.54 0)
		(mirror y)
		(unit 1)
		(exclude_from_sim no)
		(in_bom yes)
		(on_board yes)
		(dnp no)
		(fields_autoplaced yes)
		(property "Reference" "#PWR0430"
			(at 320.04 132.08 0)
			(effects
				(font
					(size 1.27 1.27)
					(thickness 0.15)
				)
				(justify left bottom)
				(hide yes)
			)
		)
		(property "Value" "GND"
			(at 328.93 134.62 0)
			(effects
				(font
					(size 1.27 1.27)
					(thickness 0.15)
				)
			)
		)
		(property "Footprint" ""
			(at 320.04 137.16 0)
			(effects
				(font
					(size 1.27 1.27)
					(thickness 0.15)
				)
				(justify left bottom)
				(hide yes)
			)
		)
		(property "Datasheet" ""
			(at 320.04 142.24 0)
			(effects
				(font
					(size 1.27 1.27)
					(thickness 0.15)
				)
				(justify left bottom)
				(hide yes)
			)
		)
		(property "Description" ""
			(at 328.93 129.54 0)
			(effects
				(font
					(size 1.27 1.27)
				)
				(hide yes)
			)
		)
		(property "Author" "Antmicro"
			(at 320.04 137.16 0)
			(effects
				(font
					(size 1.27 1.27)
					(thickness 0.15)
				)
				(justify left bottom)
				(hide yes)
			)
		)
		(property "License" "Apache-2.0"
			(at 320.04 139.7 0)
			(effects
				(font
					(size 1.27 1.27)
					(thickness 0.15)
				)
				(justify left bottom)
				(hide yes)
			)
		)
		(pin "1"
		)
		(instances
			(project "jetson-agx-thor-baseboard"
				(path ""
					(reference "#PWR0430")
					(unit 1)
				)
			)
		)
	)
	(symbol
		(lib_id "antmicroB2BConnectors:ASP-208571-01_mounting_holes")
		(at 353.06 29.21 0)
		(mirror y)
		(unit 2)
		(exclude_from_sim no)
		(in_bom yes)
		(on_board yes)
		(dnp no)
		(fields_autoplaced yes)
		(property "Reference" "J18"
			(at 341.63 21.59 0)
			(effects
				(font
					(size 1.27 1.27)
					(thickness 0.15)
				)
			)
		)
		(property "Value" "ASP-208571-01_mounting_holes"
			(at 316.23 39.37 0)
			(effects
				(font
					(size 1.27 1.27)
					(thickness 0.15)
				)
				(justify left bottom)
				(hide yes)
			)
		)
		(property "Footprint" "antmicro-footprints:ASP-208571-01_mounting_holes"
			(at 316.23 41.91 0)
			(effects
				(font
					(size 1.27 1.27)
					(thickness 0.15)
				)
				(justify left bottom)
				(hide yes)
			)
		)
		(property "Datasheet" "https://suddendocs.samtec.com/prints/asp-208571-01-mkt.pdf"
			(at 316.23 44.45 0)
			(effects
				(font
					(size 1.27 1.27)
					(thickness 0.15)
				)
				(justify left bottom)
				(hide yes)
			)
		)
		(property "Description" "FMC connector"
			(at 316.23 54.61 0)
			(effects
				(font
					(size 1.27 1.27)
				)
				(justify left bottom)
				(hide yes)
			)
		)
		(property "MPN" "ASP-208571-01"
			(at 341.63 24.13 0)
			(effects
				(font
					(size 1.27 1.27)
					(thickness 0.15)
				)
			)
		)
		(property "Manufacturer" "Samtec"
			(at 316.23 46.99 0)
			(effects
				(font
					(size 1.27 1.27)
					(thickness 0.15)
				)
				(justify left bottom)
				(hide yes)
			)
		)
		(property "Author" "Antmicro"
			(at 316.23 49.53 0)
			(effects
				(font
					(size 1.27 1.27)
					(thickness 0.15)
				)
				(justify left bottom)
				(hide yes)
			)
		)
		(property "License" "Apache-2.0"
			(at 316.23 52.07 0)
			(effects
				(font
					(size 1.27 1.27)
					(thickness 0.15)
				)
				(justify left bottom)
				(hide yes)
			)
		)
		(pin "A40"
		)
		(pin "Z01"
		)
		(pin "A09"
		)
		(pin "Y28"
		)
		(pin "D27"
		)
		(pin "B33"
		)
		(pin "C25"
		)
		(pin "C20"
		)
		(pin "Z05"
		)
		(pin "A10"
		)
		(pin "B14"
		)
		(pin "Y39"
		)
		(pin "C36"
		)
		(pin "F14"
		)
		(pin "H02"
		)
		(pin "H03"
		)
		(pin "A28"
		)
		(pin "C37"
		)
		(pin "A26"
		)
		(pin "C19"
		)
		(pin "Z06"
		)
		(pin "C28"
		)
		(pin "B10"
		)
		(pin "Z27"
		)
		(pin "B40"
		)
		(pin "Z28"
		)
		(pin "Z26"
		)
		(pin "C24"
		)
		(pin "B09"
		)
		(pin "Y27"
		)
		(pin "C08"
		)
		(pin "Z04"
		)
		(pin "A36"
		)
		(pin "C02"
		)
		(pin "A19"
		)
		(pin "E34"
		)
		(pin "K28"
		)
		(pin "K29"
		)
		(pin "G20"
		)
		(pin "G21"
		)
		(pin "A08"
		)
		(pin "B27"
		)
		(pin "D22"
		)
		(pin "F25"
		)
		(pin "C30"
		)
		(pin "D04"
		)
		(pin "A30"
		)
		(pin "A38"
		)
		(pin "B37"
		)
		(pin "G26"
		)
		(pin "G27"
		)
		(pin "C03"
		)
		(pin "F07"
		)
		(pin "D34"
		)
		(pin "G08"
		)
		(pin "G18"
		)
		(pin "G19"
		)
		(pin "G01"
		)
		(pin "A20"
		)
		(pin "M04"
		)
		(pin "M05"
		)
		(pin "Y08"
		)
		(pin "F39"
		)
		(pin "F19"
		)
		(pin "K04"
		)
		(pin "K05"
		)
		(pin "G12"
		)
		(pin "G13"
		)
		(pin "Y02"
		)
		(pin "J32"
		)
		(pin "J33"
		)
		(pin "B11"
		)
		(pin "D07"
		)
		(pin "C33"
		)
		(pin "A17"
		)
		(pin "D14"
		)
		(pin "A15"
		)
		(pin "B39"
		)
		(pin "A18"
		)
		(pin "B21"
		)
		(pin "D11"
		)
		(pin "Y15"
		)
		(pin "B16"
		)
		(pin "Y09"
		)
		(pin "F29"
		)
		(pin "J30"
		)
		(pin "J31"
		)
		(pin "B19"
		)
		(pin "A05"
		)
		(pin "B38"
		)
		(pin "E22"
		)
		(pin "D15"
		)
		(pin "L02"
		)
		(pin "L03"
		)
		(pin "Y37"
		)
		(pin "E07"
		)
		(pin "A22"
		)
		(pin "H20"
		)
		(pin "H21"
		)
		(pin "Z39"
		)
		(pin "F37"
		)
		(pin "B30"
		)
		(pin "Z15"
		)
		(pin "H36"
		)
		(pin "H37"
		)
		(pin "D16"
		)
		(pin "D37"
		)
		(pin "C40"
		)
		(pin "E29"
		)
		(pin "Y36"
		)
		(pin "K10"
		)
		(pin "K11"
		)
		(pin "F38"
		)
		(pin "B04"
		)
		(pin "F15"
		)
		(pin "J28"
		)
		(pin "J29"
		)
		(pin "B17"
		)
		(pin "E37"
		)
		(pin "E09"
		)
		(pin "Z23"
		)
		(pin "J06"
		)
		(pin "J07"
		)
		(pin "Z30"
		)
		(pin "C31"
		)
		(pin "Z37"
		)
		(pin "Z33"
		)
		(pin "Z29"
		)
		(pin "Y26"
		)
		(pin "H06"
		)
		(pin "H07"
		)
		(pin "C10"
		)
		(pin "F27"
		)
		(pin "A03"
		)
		(pin "M10"
		)
		(pin "M11"
		)
		(pin "M12"
		)
		(pin "L04"
		)
		(pin "L05"
		)
		(pin "A24"
		)
		(pin "M28"
		)
		(pin "M29"
		)
		(pin "M30"
		)
		(pin "D32"
		)
		(pin "H18"
		)
		(pin "H19"
		)
		(pin "F03"
		)
		(pin "L08"
		)
		(pin "L09"
		)
		(pin "A01"
		)
		(pin "B32"
		)
		(pin "K36"
		)
		(pin "K37"
		)
		(pin "C01"
		)
		(pin "D18"
		)
		(pin "E12"
		)
		(pin "K16"
		)
		(pin "K17"
		)
		(pin "Y11"
		)
		(pin "B31"
		)
		(pin "D28"
		)
		(pin "D23"
		)
		(pin "Z18"
		)
		(pin "D17"
		)
		(pin "F32"
		)
		(pin "B20"
		)
		(pin "C18"
		)
		(pin "A25"
		)
		(pin "Y05"
		)
		(pin "J26"
		)
		(pin "J27"
		)
		(pin "Y33"
		)
		(pin "A37"
		)
		(pin "Z21"
		)
		(pin "D09"
		)
		(pin "B26"
		)
		(pin "A35"
		)
		(pin "D20"
		)
		(pin "A11"
		)
		(pin "C15"
		)
		(pin "G14"
		)
		(pin "G15"
		)
		(pin "D01"
		)
		(pin "D21"
		)
		(pin "M34"
		)
		(pin "M35"
		)
		(pin "M36"
		)
		(pin "L32"
		)
		(pin "L33"
		)
		(pin "D31"
		)
		(pin "Z07"
		)
		(pin "M31"
		)
		(pin "M32"
		)
		(pin "M33"
		)
		(pin "K18"
		)
		(pin "K19"
		)
		(pin "F06"
		)
		(pin "Z16"
		)
		(pin "H32"
		)
		(pin "H33"
		)
		(pin "Z36"
		)
		(pin "F05"
		)
		(pin "F02"
		)
		(pin "E05"
		)
		(pin "F40"
		)
		(pin "E39"
		)
		(pin "H08"
		)
		(pin "H09"
		)
		(pin "B02"
		)
		(pin "E16"
		)
		(pin "E38"
		)
		(pin "Z12"
		)
		(pin "A34"
		)
		(pin "K08"
		)
		(pin "K09"
		)
		(pin "E31"
		)
		(pin "Y06"
		)
		(pin "F11"
		)
		(pin "F08"
		)
		(pin "A32"
		)
		(pin "Y22"
		)
		(pin "H12"
		)
		(pin "H13"
		)
		(pin "A27"
		)
		(pin "C05"
		)
		(pin "K12"
		)
		(pin "K13"
		)
		(pin "L14"
		)
		(pin "L15"
		)
		(pin "E25"
		)
		(pin "L18"
		)
		(pin "L19"
		)
		(pin "M19"
		)
		(pin "M20"
		)
		(pin "M21"
		)
		(pin "J14"
		)
		(pin "J15"
		)
		(pin "G40"
		)
		(pin "H01"
		)
		(pin "Y25"
		)
		(pin "A33"
		)
		(pin "Z35"
		)
		(pin "H38"
		)
		(pin "H39"
		)
		(pin "D29"
		)
		(pin "E02"
		)
		(pin "D10"
		)
		(pin "C12"
		)
		(pin "C26"
		)
		(pin "M40"
		)
		(pin "B24"
		)
		(pin "Y24"
		)
		(pin "F33"
		)
		(pin "F21"
		)
		(pin "E20"
		)
		(pin "D06"
		)
		(pin "C29"
		)
		(pin "E23"
		)
		(pin "J04"
		)
		(pin "J05"
		)
		(pin "B28"
		)
		(pin "K30"
		)
		(pin "K31"
		)
		(pin "B08"
		)
		(pin "L12"
		)
		(pin "L13"
		)
		(pin "J38"
		)
		(pin "J39"
		)
		(pin "D24"
		)
		(pin "E06"
		)
		(pin "D35"
		)
		(pin "G07"
		)
		(pin "C39"
		)
		(pin "E04"
		)
		(pin "L34"
		)
		(pin "L35"
		)
		(pin "D02"
		)
		(pin "Z22"
		)
		(pin "K14"
		)
		(pin "K15"
		)
		(pin "Y34"
		)
		(pin "M08"
		)
		(pin "M09"
		)
		(pin "D30"
		)
		(pin "G10"
		)
		(pin "G11"
		)
		(pin "C11"
		)
		(pin "E33"
		)
		(pin "G38"
		)
		(pin "G39"
		)
		(pin "F34"
		)
		(pin "H04"
		)
		(pin "H05"
		)
		(pin "F09"
		)
		(pin "G22"
		)
		(pin "G23"
		)
		(pin "B34"
		)
		(pin "Z20"
		)
		(pin "Y03"
		)
		(pin "M06"
		)
		(pin "M07"
		)
		(pin "K38"
		)
		(pin "K39"
		)
		(pin "Y21"
		)
		(pin "K24"
		)
		(pin "K25"
		)
		(pin "E21"
		)
		(pin "L20"
		)
		(pin "L21"
		)
		(pin "E11"
		)
		(pin "K22"
		)
		(pin "K23"
		)
		(pin "B12"
		)
		(pin "J22"
		)
		(pin "J23"
		)
		(pin "A07"
		)
		(pin "E32"
		)
		(pin "L36"
		)
		(pin "L37"
		)
		(pin "L24"
		)
		(pin "L25"
		)
		(pin "Y32"
		)
		(pin "F13"
		)
		(pin "G09"
		)
		(pin "Y01"
		)
		(pin "K06"
		)
		(pin "K07"
		)
		(pin "G28"
		)
		(pin "G29"
		)
		(pin "K40"
		)
		(pin "L01"
		)
		(pin "J02"
		)
		(pin "J03"
		)
		(pin "J12"
		)
		(pin "J13"
		)
		(pin "M25"
		)
		(pin "M26"
		)
		(pin "M27"
		)
		(pin "A13"
		)
		(pin "F20"
		)
		(pin "M37"
		)
		(pin "M38"
		)
		(pin "M39"
		)
		(pin "Y10"
		)
		(pin "G32"
		)
		(pin "G33"
		)
		(pin "A29"
		)
		(pin "L10"
		)
		(pin "L11"
		)
		(pin "G24"
		)
		(pin "G25"
		)
		(pin "E08"
		)
		(pin "C06"
		)
		(pin "A12"
		)
		(pin "F12"
		)
		(pin "C16"
		)
		(pin "Z09"
		)
		(pin "E19"
		)
		(pin "D03"
		)
		(pin "E24"
		)
		(pin "F23"
		)
		(pin "G16"
		)
		(pin "G17"
		)
		(pin "A23"
		)
		(pin "D12"
		)
		(pin "C07"
		)
		(pin "L30"
		)
		(pin "L31"
		)
		(pin "B29"
		)
		(pin "B15"
		)
		(pin "J16"
		)
		(pin "J17"
		)
		(pin "K26"
		)
		(pin "K27"
		)
		(pin "A16"
		)
		(pin "E01"
		)
		(pin "Y12"
		)
		(pin "G04"
		)
		(pin "C32"
		)
		(pin "B22"
		)
		(pin "Y16"
		)
		(pin "G34"
		)
		(pin "G35"
		)
		(pin "A02"
		)
		(pin "D40"
		)
		(pin "Y38"
		)
		(pin "D08"
		)
		(pin "C27"
		)
		(pin "J36"
		)
		(pin "J37"
		)
		(pin "K34"
		)
		(pin "K35"
		)
		(pin "M02"
		)
		(pin "M03"
		)
		(pin "B01"
		)
		(pin "E35"
		)
		(pin "Y13"
		)
		(pin "L26"
		)
		(pin "L27"
		)
		(pin "G36"
		)
		(pin "G37"
		)
		(pin "K32"
		)
		(pin "K33"
		)
		(pin "Y14"
		)
		(pin "D13"
		)
		(pin "D25"
		)
		(pin "F10"
		)
		(pin "E10"
		)
		(pin "E26"
		)
		(pin "E18"
		)
		(pin "F24"
		)
		(pin "Z10"
		)
		(pin "H40"
		)
		(pin "J01"
		)
		(pin "G05"
		)
		(pin "Z17"
		)
		(pin "F22"
		)
		(pin "A14"
		)
		(pin "E30"
		)
		(pin "Z13"
		)
		(pin "H22"
		)
		(pin "H23"
		)
		(pin "E28"
		)
		(pin "F36"
		)
		(pin "B18"
		)
		(pin "Z08"
		)
		(pin "H34"
		)
		(pin "H35"
		)
		(pin "J08"
		)
		(pin "J09"
		)
		(pin "C23"
		)
		(pin "J40"
		)
		(pin "K01"
		)
		(pin "Y07"
		)
		(pin "H14"
		)
		(pin "H15"
		)
		(pin "D36"
		)
		(pin "Y35"
		)
		(pin "C13"
		)
		(pin "F30"
		)
		(pin "L40"
		)
		(pin "M01"
		)
		(pin "F17"
		)
		(pin "Z03"
		)
		(pin "F28"
		)
		(pin "Z40"
		)
		(pin "A39"
		)
		(pin "Y40"
		)
		(pin "M13"
		)
		(pin "M14"
		)
		(pin "M15"
		)
		(pin "D38"
		)
		(pin "Y29"
		)
		(pin "F18"
		)
		(pin "E40"
		)
		(pin "B36"
		)
		(pin "E15"
		)
		(pin "C09"
		)
		(pin "E27"
		)
		(pin "Z31"
		)
		(pin "A06"
		)
		(pin "L22"
		)
		(pin "L23"
		)
		(pin "C34"
		)
		(pin "Y19"
		)
		(pin "J18"
		)
		(pin "J19"
		)
		(pin "L38"
		)
		(pin "L39"
		)
		(pin "G03"
		)
		(pin "F01"
		)
		(pin "M16"
		)
		(pin "M17"
		)
		(pin "M18"
		)
		(pin "J20"
		)
		(pin "J21"
		)
		(pin "H26"
		)
		(pin "H27"
		)
		(pin "Y20"
		)
		(pin "H28"
		)
		(pin "H29"
		)
		(pin "Z34"
		)
		(pin "D26"
		)
		(pin "Y31"
		)
		(pin "G06"
		)
		(pin "Z11"
		)
		(pin "H30"
		)
		(pin "H31"
		)
		(pin "Y04"
		)
		(pin "Z24"
		)
		(pin "D33"
		)
		(pin "F35"
		)
		(pin "B35"
		)
		(pin "B06"
		)
		(pin "B23"
		)
		(pin "M22"
		)
		(pin "M23"
		)
		(pin "M24"
		)
		(pin "Y30"
		)
		(pin "B07"
		)
		(pin "C21"
		)
		(pin "H16"
		)
		(pin "H17"
		)
		(pin "H24"
		)
		(pin "H25"
		)
		(pin "C04"
		)
		(pin "A31"
		)
		(pin "A04"
		)
		(pin "E14"
		)
		(pin "Z38"
		)
		(pin "E17"
		)
		(pin "A21"
		)
		(pin "B03"
		)
		(pin "F04"
		)
		(pin "B13"
		)
		(pin "C14"
		)
		(pin "Z19"
		)
		(pin "Y18"
		)
		(pin "Z14"
		)
		(pin "Z25"
		)
		(pin "J24"
		)
		(pin "J25"
		)
		(pin "H10"
		)
		(pin "H11"
		)
		(pin "K20"
		)
		(pin "K21"
		)
		(pin "F31"
		)
		(pin "F16"
		)
		(pin "E13"
		)
		(pin "F26"
		)
		(pin "C22"
		)
		(pin "E36"
		)
		(pin "J34"
		)
		(pin "J35"
		)
		(pin "C35"
		)
		(pin "L16"
		)
		(pin "L17"
		)
		(pin "J10"
		)
		(pin "J11"
		)
		(pin "L06"
		)
		(pin "L07"
		)
		(pin "D19"
		)
		(pin "Z02"
		)
		(pin "D39"
		)
		(pin "Z32"
		)
		(pin "B25"
		)
		(pin "B05"
		)
		(pin "G30"
		)
		(pin "G31"
		)
		(pin "K02"
		)
		(pin "K03"
		)
		(pin "E03"
		)
		(pin "C38"
		)
		(pin "C17"
		)
		(pin "G02"
		)
		(pin "Y23"
		)
		(pin "D05"
		)
		(pin "L28"
		)
		(pin "L29"
		)
		(pin "Y17"
		)
		(instances
			(project "jetson-agx-thor-baseboard"
				(path ""
					(reference "J18")
					(unit 2)
				)
			)
		)
	)
	(symbol
		(lib_id "antmicropower:GND")
		(at 247.65 129.54 0)
		(mirror y)
		(unit 1)
		(exclude_from_sim no)
		(in_bom yes)
		(on_board yes)
		(dnp no)
		(fields_autoplaced yes)
		(property "Reference" "#PWR0437"
			(at 238.76 132.08 0)
			(effects
				(font
					(size 1.27 1.27)
					(thickness 0.15)
				)
				(justify left bottom)
				(hide yes)
			)
		)
		(property "Value" "GND"
			(at 247.65 134.62 0)
			(effects
				(font
					(size 1.27 1.27)
					(thickness 0.15)
				)
			)
		)
		(property "Footprint" ""
			(at 238.76 137.16 0)
			(effects
				(font
					(size 1.27 1.27)
					(thickness 0.15)
				)
				(justify left bottom)
				(hide yes)
			)
		)
		(property "Datasheet" ""
			(at 238.76 142.24 0)
			(effects
				(font
					(size 1.27 1.27)
					(thickness 0.15)
				)
				(justify left bottom)
				(hide yes)
			)
		)
		(property "Description" ""
			(at 247.65 129.54 0)
			(effects
				(font
					(size 1.27 1.27)
				)
				(hide yes)
			)
		)
		(property "Author" "Antmicro"
			(at 238.76 137.16 0)
			(effects
				(font
					(size 1.27 1.27)
					(thickness 0.15)
				)
				(justify left bottom)
				(hide yes)
			)
		)
		(property "License" "Apache-2.0"
			(at 238.76 139.7 0)
			(effects
				(font
					(size 1.27 1.27)
					(thickness 0.15)
				)
				(justify left bottom)
				(hide yes)
			)
		)
		(pin "1"
		)
		(instances
			(project "jetson-agx-thor-baseboard"
				(path ""
					(reference "#PWR0437")
					(unit 1)
				)
			)
		)
	)
	(symbol
		(lib_id "antmicroResistors0402:R_0R_0402")
		(at 189.23 222.25 0)
		(unit 1)
		(exclude_from_sim no)
		(in_bom yes)
		(on_board yes)
		(dnp no)
		(property "Reference" "R49"
			(at 191.77 217.805 0)
			(effects
				(font
					(size 1.27 1.27)
					(thickness 0.15)
				)
			)
		)
		(property "Value" "R_0R_0402"
			(at 209.55 234.95 0)
			(effects
				(font
					(size 1.27 1.27)
					(thickness 0.15)
				)
				(justify left bottom)
				(hide yes)
			)
		)
		(property "Footprint" "antmicro-footprints:R_0402_1005Metric"
			(at 209.55 237.49 0)
			(effects
				(font
					(size 1.27 1.27)
					(thickness 0.15)
				)
				(justify left bottom)
				(hide yes)
			)
		)
		(property "Datasheet" "https://industrial.panasonic.com/cdbs/www-data/pdf/RDA0000/AOA0000C301.pdf"
			(at 209.55 240.03 0)
			(effects
				(font
					(size 1.27 1.27)
					(thickness 0.15)
				)
				(justify left bottom)
				(hide yes)
			)
		)
		(property "Description" "SMD Chip Resistor, Jumper, 0 ohm, 100 mW, 0402 [1005 Metric], Thick Film, General Purpose"
			(at 209.55 255.27 0)
			(effects
				(font
					(size 1.27 1.27)
				)
				(justify left bottom)
				(hide yes)
			)
		)
		(property "MPN" "ERJ2GE0R00X"
			(at 209.55 242.57 0)
			(effects
				(font
					(size 1.27 1.27)
					(thickness 0.15)
				)
				(justify left bottom)
				(hide yes)
			)
		)
		(property "Manufacturer" "Panasonic"
			(at 209.55 245.11 0)
			(effects
				(font
					(size 1.27 1.27)
					(thickness 0.15)
				)
				(justify left bottom)
				(hide yes)
			)
		)
		(property "License" "Apache-2.0"
			(at 209.55 247.65 0)
			(effects
				(font
					(size 1.27 1.27)
					(thickness 0.15)
				)
				(justify left bottom)
				(hide yes)
			)
		)
		(property "Author" "Antmicro"
			(at 209.55 250.19 0)
			(effects
				(font
					(size 1.27 1.27)
					(thickness 0.15)
				)
				(justify left bottom)
				(hide yes)
			)
		)
		(property "Val" "0R"
			(at 191.77 219.71 0)
			(effects
				(font
					(size 1.27 1.27)
					(thickness 0.15)
				)
			)
		)
		(property "Tolerance" "~"
			(at 209.55 232.41 0)
			(effects
				(font
					(size 1.27 1.27)
				)
				(justify left bottom)
				(hide yes)
			)
		)
		(property "Current" "1A"
			(at 209.55 252.73 0)
			(effects
				(font
					(size 1.27 1.27)
					(thickness 0.15)
				)
				(justify left bottom)
				(hide yes)
			)
		)
		(pin "2"
		)
		(pin "1"
		)
		(instances
			(project ""
				(path ""
					(reference "R49")
					(unit 1)
				)
			)
		)
	)
	(symbol
		(lib_id "antmicroCapacitors0402:C_220n_0402")
		(at 193.04 245.11 0)
		(unit 1)
		(exclude_from_sim no)
		(in_bom yes)
		(on_board yes)
		(dnp no)
		(fields_autoplaced yes)
		(property "Reference" "C214"
			(at 195.5864 248.92 0)
			(effects
				(font
					(size 1.27 1.27)
					(thickness 0.15)
				)
			)
		)
		(property "Value" "C_220n_0402"
			(at 208.28 267.97 0)
			(effects
				(font
					(size 1.27 1.27)
					(thickness 0.15)
				)
				(justify left bottom)
				(hide yes)
			)
		)
		(property "Footprint" "antmicro-footprints:C_0402_1005Metric"
			(at 208.28 270.51 0)
			(effects
				(font
					(size 1.27 1.27)
					(thickness 0.15)
				)
				(justify left bottom)
				(hide yes)
			)
		)
		(property "Datasheet" "https://www.yageo.com/en/Chart/Download/pdf/CC0402KRX5R6BB224"
			(at 208.28 273.05 0)
			(effects
				(font
					(size 1.27 1.27)
					(thickness 0.15)
				)
				(justify left bottom)
				(hide yes)
			)
		)
		(property "Description" "SMD Multilayer Ceramic Capacitor, 0.22 µF, 10 V, 0402 [1005 Metric], ± 10%, X5R, CC Series"
			(at 193.04 245.11 0)
			(effects
				(font
					(size 1.27 1.27)
				)
				(hide yes)
			)
		)
		(property "MPN" "CC0402KRX5R6BB224"
			(at 208.28 275.59 0)
			(effects
				(font
					(size 1.27 1.27)
					(thickness 0.15)
				)
				(justify left bottom)
				(hide yes)
			)
		)
		(property "Val" "220n"
			(at 195.5864 251.46 0)
			(effects
				(font
					(size 1.27 1.27)
					(thickness 0.15)
				)
			)
		)
		(property "Voltage" "25V"
			(at 208.28 255.27 0)
			(effects
				(font
					(size 1.27 1.27)
					(thickness 0.15)
				)
				(justify left bottom)
				(hide yes)
			)
		)
		(property "Dielectric" "X7R"
			(at 208.28 257.81 0)
			(effects
				(font
					(size 1.27 1.27)
					(thickness 0.15)
				)
				(justify left bottom)
				(hide yes)
			)
		)
		(property "Manufacturer" "YAGEO"
			(at 208.28 260.35 0)
			(effects
				(font
					(size 1.27 1.27)
					(thickness 0.15)
				)
				(justify left bottom)
				(hide yes)
			)
		)
		(property "License" "Apache-2.0"
			(at 208.28 262.89 0)
			(effects
				(font
					(size 1.27 1.27)
					(thickness 0.15)
				)
				(justify left bottom)
				(hide yes)
			)
		)
		(property "Author" "Antmicro"
			(at 208.28 265.43 0)
			(effects
				(font
					(size 1.27 1.27)
					(thickness 0.15)
				)
				(justify left bottom)
				(hide yes)
			)
		)
		(property "Public" "False"
			(at 213.36 278.13 0)
			(effects
				(font
					(size 1.27 1.27)
				)
				(justify left bottom)
				(hide yes)
			)
		)
		(pin "2"
		)
		(pin "1"
		)
		(instances
			(project "jetson-agx-thor-baseboard"
				(path ""
					(reference "C214")
					(unit 1)
				)
			)
		)
	)
	(symbol
		(lib_id "antmicroB2BConnectors:ASP-208571-01_mounting_holes")
		(at 271.78 29.21 0)
		(mirror y)
		(unit 3)
		(exclude_from_sim no)
		(in_bom yes)
		(on_board yes)
		(dnp no)
		(fields_autoplaced yes)
		(property "Reference" "J18"
			(at 260.35 21.59 0)
			(effects
				(font
					(size 1.27 1.27)
					(thickness 0.15)
				)
			)
		)
		(property "Value" "ASP-208571-01_mounting_holes"
			(at 234.95 39.37 0)
			(effects
				(font
					(size 1.27 1.27)
					(thickness 0.15)
				)
				(justify left bottom)
				(hide yes)
			)
		)
		(property "Footprint" "antmicro-footprints:ASP-208571-01_mounting_holes"
			(at 234.95 41.91 0)
			(effects
				(font
					(size 1.27 1.27)
					(thickness 0.15)
				)
				(justify left bottom)
				(hide yes)
			)
		)
		(property "Datasheet" "https://suddendocs.samtec.com/prints/asp-208571-01-mkt.pdf"
			(at 234.95 44.45 0)
			(effects
				(font
					(size 1.27 1.27)
					(thickness 0.15)
				)
				(justify left bottom)
				(hide yes)
			)
		)
		(property "Description" "FMC connector"
			(at 234.95 54.61 0)
			(effects
				(font
					(size 1.27 1.27)
				)
				(justify left bottom)
				(hide yes)
			)
		)
		(property "MPN" "ASP-208571-01"
			(at 260.35 24.13 0)
			(effects
				(font
					(size 1.27 1.27)
					(thickness 0.15)
				)
			)
		)
		(property "Manufacturer" "Samtec"
			(at 234.95 46.99 0)
			(effects
				(font
					(size 1.27 1.27)
					(thickness 0.15)
				)
				(justify left bottom)
				(hide yes)
			)
		)
		(property "Author" "Antmicro"
			(at 234.95 49.53 0)
			(effects
				(font
					(size 1.27 1.27)
					(thickness 0.15)
				)
				(justify left bottom)
				(hide yes)
			)
		)
		(property "License" "Apache-2.0"
			(at 234.95 52.07 0)
			(effects
				(font
					(size 1.27 1.27)
					(thickness 0.15)
				)
				(justify left bottom)
				(hide yes)
			)
		)
		(pin "A40"
		)
		(pin "Z01"
		)
		(pin "A09"
		)
		(pin "Y28"
		)
		(pin "D27"
		)
		(pin "B33"
		)
		(pin "C25"
		)
		(pin "C20"
		)
		(pin "Z05"
		)
		(pin "A10"
		)
		(pin "B14"
		)
		(pin "Y39"
		)
		(pin "C36"
		)
		(pin "F14"
		)
		(pin "H02"
		)
		(pin "H03"
		)
		(pin "A28"
		)
		(pin "C37"
		)
		(pin "A26"
		)
		(pin "C19"
		)
		(pin "Z06"
		)
		(pin "C28"
		)
		(pin "B10"
		)
		(pin "Z27"
		)
		(pin "B40"
		)
		(pin "Z28"
		)
		(pin "Z26"
		)
		(pin "C24"
		)
		(pin "B09"
		)
		(pin "Y27"
		)
		(pin "C08"
		)
		(pin "Z04"
		)
		(pin "A36"
		)
		(pin "C02"
		)
		(pin "A19"
		)
		(pin "E34"
		)
		(pin "K28"
		)
		(pin "K29"
		)
		(pin "G20"
		)
		(pin "G21"
		)
		(pin "A08"
		)
		(pin "B27"
		)
		(pin "D22"
		)
		(pin "F25"
		)
		(pin "C30"
		)
		(pin "D04"
		)
		(pin "A30"
		)
		(pin "A38"
		)
		(pin "B37"
		)
		(pin "G26"
		)
		(pin "G27"
		)
		(pin "C03"
		)
		(pin "F07"
		)
		(pin "D34"
		)
		(pin "G08"
		)
		(pin "G18"
		)
		(pin "G19"
		)
		(pin "G01"
		)
		(pin "A20"
		)
		(pin "M04"
		)
		(pin "M05"
		)
		(pin "Y08"
		)
		(pin "F39"
		)
		(pin "F19"
		)
		(pin "K04"
		)
		(pin "K05"
		)
		(pin "G12"
		)
		(pin "G13"
		)
		(pin "Y02"
		)
		(pin "J32"
		)
		(pin "J33"
		)
		(pin "B11"
		)
		(pin "D07"
		)
		(pin "C33"
		)
		(pin "A17"
		)
		(pin "D14"
		)
		(pin "A15"
		)
		(pin "B39"
		)
		(pin "A18"
		)
		(pin "B21"
		)
		(pin "D11"
		)
		(pin "Y15"
		)
		(pin "B16"
		)
		(pin "Y09"
		)
		(pin "F29"
		)
		(pin "J30"
		)
		(pin "J31"
		)
		(pin "B19"
		)
		(pin "A05"
		)
		(pin "B38"
		)
		(pin "E22"
		)
		(pin "D15"
		)
		(pin "L02"
		)
		(pin "L03"
		)
		(pin "Y37"
		)
		(pin "E07"
		)
		(pin "A22"
		)
		(pin "H20"
		)
		(pin "H21"
		)
		(pin "Z39"
		)
		(pin "F37"
		)
		(pin "B30"
		)
		(pin "Z15"
		)
		(pin "H36"
		)
		(pin "H37"
		)
		(pin "D16"
		)
		(pin "D37"
		)
		(pin "C40"
		)
		(pin "E29"
		)
		(pin "Y36"
		)
		(pin "K10"
		)
		(pin "K11"
		)
		(pin "F38"
		)
		(pin "B04"
		)
		(pin "F15"
		)
		(pin "J28"
		)
		(pin "J29"
		)
		(pin "B17"
		)
		(pin "E37"
		)
		(pin "E09"
		)
		(pin "Z23"
		)
		(pin "J06"
		)
		(pin "J07"
		)
		(pin "Z30"
		)
		(pin "C31"
		)
		(pin "Z37"
		)
		(pin "Z33"
		)
		(pin "Z29"
		)
		(pin "Y26"
		)
		(pin "H06"
		)
		(pin "H07"
		)
		(pin "C10"
		)
		(pin "F27"
		)
		(pin "A03"
		)
		(pin "M10"
		)
		(pin "M11"
		)
		(pin "M12"
		)
		(pin "L04"
		)
		(pin "L05"
		)
		(pin "A24"
		)
		(pin "M28"
		)
		(pin "M29"
		)
		(pin "M30"
		)
		(pin "D32"
		)
		(pin "H18"
		)
		(pin "H19"
		)
		(pin "F03"
		)
		(pin "L08"
		)
		(pin "L09"
		)
		(pin "A01"
		)
		(pin "B32"
		)
		(pin "K36"
		)
		(pin "K37"
		)
		(pin "C01"
		)
		(pin "D18"
		)
		(pin "E12"
		)
		(pin "K16"
		)
		(pin "K17"
		)
		(pin "Y11"
		)
		(pin "B31"
		)
		(pin "D28"
		)
		(pin "D23"
		)
		(pin "Z18"
		)
		(pin "D17"
		)
		(pin "F32"
		)
		(pin "B20"
		)
		(pin "C18"
		)
		(pin "A25"
		)
		(pin "Y05"
		)
		(pin "J26"
		)
		(pin "J27"
		)
		(pin "Y33"
		)
		(pin "A37"
		)
		(pin "Z21"
		)
		(pin "D09"
		)
		(pin "B26"
		)
		(pin "A35"
		)
		(pin "D20"
		)
		(pin "A11"
		)
		(pin "C15"
		)
		(pin "G14"
		)
		(pin "G15"
		)
		(pin "D01"
		)
		(pin "D21"
		)
		(pin "M34"
		)
		(pin "M35"
		)
		(pin "M36"
		)
		(pin "L32"
		)
		(pin "L33"
		)
		(pin "D31"
		)
		(pin "Z07"
		)
		(pin "M31"
		)
		(pin "M32"
		)
		(pin "M33"
		)
		(pin "K18"
		)
		(pin "K19"
		)
		(pin "F06"
		)
		(pin "Z16"
		)
		(pin "H32"
		)
		(pin "H33"
		)
		(pin "Z36"
		)
		(pin "F05"
		)
		(pin "F02"
		)
		(pin "E05"
		)
		(pin "F40"
		)
		(pin "E39"
		)
		(pin "H08"
		)
		(pin "H09"
		)
		(pin "B02"
		)
		(pin "E16"
		)
		(pin "E38"
		)
		(pin "Z12"
		)
		(pin "A34"
		)
		(pin "K08"
		)
		(pin "K09"
		)
		(pin "E31"
		)
		(pin "Y06"
		)
		(pin "F11"
		)
		(pin "F08"
		)
		(pin "A32"
		)
		(pin "Y22"
		)
		(pin "H12"
		)
		(pin "H13"
		)
		(pin "A27"
		)
		(pin "C05"
		)
		(pin "K12"
		)
		(pin "K13"
		)
		(pin "L14"
		)
		(pin "L15"
		)
		(pin "E25"
		)
		(pin "L18"
		)
		(pin "L19"
		)
		(pin "M19"
		)
		(pin "M20"
		)
		(pin "M21"
		)
		(pin "J14"
		)
		(pin "J15"
		)
		(pin "G40"
		)
		(pin "H01"
		)
		(pin "Y25"
		)
		(pin "A33"
		)
		(pin "Z35"
		)
		(pin "H38"
		)
		(pin "H39"
		)
		(pin "D29"
		)
		(pin "E02"
		)
		(pin "D10"
		)
		(pin "C12"
		)
		(pin "C26"
		)
		(pin "M40"
		)
		(pin "B24"
		)
		(pin "Y24"
		)
		(pin "F33"
		)
		(pin "F21"
		)
		(pin "E20"
		)
		(pin "D06"
		)
		(pin "C29"
		)
		(pin "E23"
		)
		(pin "J04"
		)
		(pin "J05"
		)
		(pin "B28"
		)
		(pin "K30"
		)
		(pin "K31"
		)
		(pin "B08"
		)
		(pin "L12"
		)
		(pin "L13"
		)
		(pin "J38"
		)
		(pin "J39"
		)
		(pin "D24"
		)
		(pin "E06"
		)
		(pin "D35"
		)
		(pin "G07"
		)
		(pin "C39"
		)
		(pin "E04"
		)
		(pin "L34"
		)
		(pin "L35"
		)
		(pin "D02"
		)
		(pin "Z22"
		)
		(pin "K14"
		)
		(pin "K15"
		)
		(pin "Y34"
		)
		(pin "M08"
		)
		(pin "M09"
		)
		(pin "D30"
		)
		(pin "G10"
		)
		(pin "G11"
		)
		(pin "C11"
		)
		(pin "E33"
		)
		(pin "G38"
		)
		(pin "G39"
		)
		(pin "F34"
		)
		(pin "H04"
		)
		(pin "H05"
		)
		(pin "F09"
		)
		(pin "G22"
		)
		(pin "G23"
		)
		(pin "B34"
		)
		(pin "Z20"
		)
		(pin "Y03"
		)
		(pin "M06"
		)
		(pin "M07"
		)
		(pin "K38"
		)
		(pin "K39"
		)
		(pin "Y21"
		)
		(pin "K24"
		)
		(pin "K25"
		)
		(pin "E21"
		)
		(pin "L20"
		)
		(pin "L21"
		)
		(pin "E11"
		)
		(pin "K22"
		)
		(pin "K23"
		)
		(pin "B12"
		)
		(pin "J22"
		)
		(pin "J23"
		)
		(pin "A07"
		)
		(pin "E32"
		)
		(pin "L36"
		)
		(pin "L37"
		)
		(pin "L24"
		)
		(pin "L25"
		)
		(pin "Y32"
		)
		(pin "F13"
		)
		(pin "G09"
		)
		(pin "Y01"
		)
		(pin "K06"
		)
		(pin "K07"
		)
		(pin "G28"
		)
		(pin "G29"
		)
		(pin "K40"
		)
		(pin "L01"
		)
		(pin "J02"
		)
		(pin "J03"
		)
		(pin "J12"
		)
		(pin "J13"
		)
		(pin "M25"
		)
		(pin "M26"
		)
		(pin "M27"
		)
		(pin "A13"
		)
		(pin "F20"
		)
		(pin "M37"
		)
		(pin "M38"
		)
		(pin "M39"
		)
		(pin "Y10"
		)
		(pin "G32"
		)
		(pin "G33"
		)
		(pin "A29"
		)
		(pin "L10"
		)
		(pin "L11"
		)
		(pin "G24"
		)
		(pin "G25"
		)
		(pin "E08"
		)
		(pin "C06"
		)
		(pin "A12"
		)
		(pin "F12"
		)
		(pin "C16"
		)
		(pin "Z09"
		)
		(pin "E19"
		)
		(pin "D03"
		)
		(pin "E24"
		)
		(pin "F23"
		)
		(pin "G16"
		)
		(pin "G17"
		)
		(pin "A23"
		)
		(pin "D12"
		)
		(pin "C07"
		)
		(pin "L30"
		)
		(pin "L31"
		)
		(pin "B29"
		)
		(pin "B15"
		)
		(pin "J16"
		)
		(pin "J17"
		)
		(pin "K26"
		)
		(pin "K27"
		)
		(pin "A16"
		)
		(pin "E01"
		)
		(pin "Y12"
		)
		(pin "G04"
		)
		(pin "C32"
		)
		(pin "B22"
		)
		(pin "Y16"
		)
		(pin "G34"
		)
		(pin "G35"
		)
		(pin "A02"
		)
		(pin "D40"
		)
		(pin "Y38"
		)
		(pin "D08"
		)
		(pin "C27"
		)
		(pin "J36"
		)
		(pin "J37"
		)
		(pin "K34"
		)
		(pin "K35"
		)
		(pin "M02"
		)
		(pin "M03"
		)
		(pin "B01"
		)
		(pin "E35"
		)
		(pin "Y13"
		)
		(pin "L26"
		)
		(pin "L27"
		)
		(pin "G36"
		)
		(pin "G37"
		)
		(pin "K32"
		)
		(pin "K33"
		)
		(pin "Y14"
		)
		(pin "D13"
		)
		(pin "D25"
		)
		(pin "F10"
		)
		(pin "E10"
		)
		(pin "E26"
		)
		(pin "E18"
		)
		(pin "F24"
		)
		(pin "Z10"
		)
		(pin "H40"
		)
		(pin "J01"
		)
		(pin "G05"
		)
		(pin "Z17"
		)
		(pin "F22"
		)
		(pin "A14"
		)
		(pin "E30"
		)
		(pin "Z13"
		)
		(pin "H22"
		)
		(pin "H23"
		)
		(pin "E28"
		)
		(pin "F36"
		)
		(pin "B18"
		)
		(pin "Z08"
		)
		(pin "H34"
		)
		(pin "H35"
		)
		(pin "J08"
		)
		(pin "J09"
		)
		(pin "C23"
		)
		(pin "J40"
		)
		(pin "K01"
		)
		(pin "Y07"
		)
		(pin "H14"
		)
		(pin "H15"
		)
		(pin "D36"
		)
		(pin "Y35"
		)
		(pin "C13"
		)
		(pin "F30"
		)
		(pin "L40"
		)
		(pin "M01"
		)
		(pin "F17"
		)
		(pin "Z03"
		)
		(pin "F28"
		)
		(pin "Z40"
		)
		(pin "A39"
		)
		(pin "Y40"
		)
		(pin "M13"
		)
		(pin "M14"
		)
		(pin "M15"
		)
		(pin "D38"
		)
		(pin "Y29"
		)
		(pin "F18"
		)
		(pin "E40"
		)
		(pin "B36"
		)
		(pin "E15"
		)
		(pin "C09"
		)
		(pin "E27"
		)
		(pin "Z31"
		)
		(pin "A06"
		)
		(pin "L22"
		)
		(pin "L23"
		)
		(pin "C34"
		)
		(pin "Y19"
		)
		(pin "J18"
		)
		(pin "J19"
		)
		(pin "L38"
		)
		(pin "L39"
		)
		(pin "G03"
		)
		(pin "F01"
		)
		(pin "M16"
		)
		(pin "M17"
		)
		(pin "M18"
		)
		(pin "J20"
		)
		(pin "J21"
		)
		(pin "H26"
		)
		(pin "H27"
		)
		(pin "Y20"
		)
		(pin "H28"
		)
		(pin "H29"
		)
		(pin "Z34"
		)
		(pin "D26"
		)
		(pin "Y31"
		)
		(pin "G06"
		)
		(pin "Z11"
		)
		(pin "H30"
		)
		(pin "H31"
		)
		(pin "Y04"
		)
		(pin "Z24"
		)
		(pin "D33"
		)
		(pin "F35"
		)
		(pin "B35"
		)
		(pin "B06"
		)
		(pin "B23"
		)
		(pin "M22"
		)
		(pin "M23"
		)
		(pin "M24"
		)
		(pin "Y30"
		)
		(pin "B07"
		)
		(pin "C21"
		)
		(pin "H16"
		)
		(pin "H17"
		)
		(pin "H24"
		)
		(pin "H25"
		)
		(pin "C04"
		)
		(pin "A31"
		)
		(pin "A04"
		)
		(pin "E14"
		)
		(pin "Z38"
		)
		(pin "E17"
		)
		(pin "A21"
		)
		(pin "B03"
		)
		(pin "F04"
		)
		(pin "B13"
		)
		(pin "C14"
		)
		(pin "Z19"
		)
		(pin "Y18"
		)
		(pin "Z14"
		)
		(pin "Z25"
		)
		(pin "J24"
		)
		(pin "J25"
		)
		(pin "H10"
		)
		(pin "H11"
		)
		(pin "K20"
		)
		(pin "K21"
		)
		(pin "F31"
		)
		(pin "F16"
		)
		(pin "E13"
		)
		(pin "F26"
		)
		(pin "C22"
		)
		(pin "E36"
		)
		(pin "J34"
		)
		(pin "J35"
		)
		(pin "C35"
		)
		(pin "L16"
		)
		(pin "L17"
		)
		(pin "J10"
		)
		(pin "J11"
		)
		(pin "L06"
		)
		(pin "L07"
		)
		(pin "D19"
		)
		(pin "Z02"
		)
		(pin "D39"
		)
		(pin "Z32"
		)
		(pin "B25"
		)
		(pin "B05"
		)
		(pin "G30"
		)
		(pin "G31"
		)
		(pin "K02"
		)
		(pin "K03"
		)
		(pin "E03"
		)
		(pin "C38"
		)
		(pin "C17"
		)
		(pin "G02"
		)
		(pin "Y23"
		)
		(pin "D05"
		)
		(pin "L28"
		)
		(pin "L29"
		)
		(pin "Y17"
		)
		(instances
			(project "jetson-agx-thor-baseboard"
				(path ""
					(reference "J18")
					(unit 3)
				)
			)
		)
	)
	(symbol
		(lib_id "antmicroB2BConnectors:Plug_Samtec_UMPT_1x6_UMPT-06-02.5-L-V-S-W-TR")
		(at 337.82 223.52 0)
		(mirror y)
		(unit 1)
		(exclude_from_sim no)
		(in_bom yes)
		(on_board yes)
		(dnp no)
		(fields_autoplaced yes)
		(property "Reference" "J8"
			(at 332.105 215.9 0)
			(effects
				(font
					(size 1.27 1.27)
					(thickness 0.15)
				)
			)
		)
		(property "Value" "Plug_Samtec_UMPT_1x6_UMPT-06-02.5-L-V-S-W-TR"
			(at 314.96 231.14 0)
			(effects
				(font
					(size 1.27 1.27)
					(thickness 0.15)
				)
				(justify left bottom)
				(hide yes)
			)
		)
		(property "Footprint" "antmicro-footprints:Conn_Plug_Samtec_UMPT_1x6_UMPT-06-02.5-L-V-S-W-TR"
			(at 314.96 233.68 0)
			(effects
				(font
					(size 1.27 1.27)
					(thickness 0.15)
				)
				(justify left bottom)
				(hide yes)
			)
		)
		(property "Datasheet" "https://suddendocs.samtec.com/catalog_english/umpt.pdf"
			(at 314.96 236.22 0)
			(effects
				(font
					(size 1.27 1.27)
					(thickness 0.15)
				)
				(justify left bottom)
				(hide yes)
			)
		)
		(property "Description" "2.00 mm mPOWER® Ultra Micro Power Terminal, Vertical"
			(at 314.96 248.92 0)
			(effects
				(font
					(size 1.27 1.27)
					(thickness 0.15)
				)
				(justify left bottom)
				(hide yes)
			)
		)
		(property "MPN" "UMPT-06-02.5-L-V-S-W-TR"
			(at 332.105 218.44 0)
			(effects
				(font
					(size 1.27 1.27)
					(thickness 0.15)
				)
			)
		)
		(property "Manufacturer" "Samtec"
			(at 314.96 241.3 0)
			(effects
				(font
					(size 1.27 1.27)
					(thickness 0.15)
				)
				(justify left bottom)
				(hide yes)
			)
		)
		(property "Author" "Antmicro"
			(at 314.96 243.84 0)
			(effects
				(font
					(size 1.27 1.27)
					(thickness 0.15)
				)
				(justify left bottom)
				(hide yes)
			)
		)
		(property "License" "Apache-2.0"
			(at 314.96 246.38 0)
			(effects
				(font
					(size 1.27 1.27)
					(thickness 0.15)
				)
				(justify left bottom)
				(hide yes)
			)
		)
		(pin "1"
		)
		(pin "MP2"
		)
		(pin "MP1"
		)
		(pin "5"
		)
		(pin "6"
		)
		(pin "3"
		)
		(pin "4"
		)
		(pin "2"
		)
		(instances
			(project ""
				(path ""
					(reference "J8")
					(unit 1)
				)
			)
		)
	)
	(symbol
		(lib_id "antmicroResistors0603:R_0R_22.4A_0603")
		(at 387.35 205.74 0)
		(mirror y)
		(unit 1)
		(exclude_from_sim no)
		(in_bom no)
		(on_board yes)
		(dnp yes)
		(property "Reference" "R248"
			(at 384.81 203.835 0)
			(effects
				(font
					(size 1.27 1.27)
					(thickness 0.15)
				)
			)
		)
		(property "Value" "R_0R_22.4A_0603"
			(at 384.81 196.85 0)
			(effects
				(font
					(size 1.27 1.27)
					(thickness 0.15)
				)
				(hide yes)
			)
		)
		(property "Footprint" "antmicro-footprints:R_0603_1608Metric"
			(at 372.11 215.9 0)
			(effects
				(font
					(size 1.27 1.27)
					(thickness 0.15)
				)
				(justify left bottom)
				(hide yes)
			)
		)
		(property "Datasheet" "https://fscdn.rohm.com/en/products/databook/datasheet/passive/resistor/chip_resistor/pmr-jpw-e.pdf"
			(at 372.11 218.44 0)
			(effects
				(font
					(size 1.27 1.27)
					(thickness 0.15)
				)
				(justify left bottom)
				(hide yes)
			)
		)
		(property "Description" "SMD Chip Resistor"
			(at 387.35 205.74 0)
			(effects
				(font
					(size 1.27 1.27)
				)
				(hide yes)
			)
		)
		(property "MPN" "PMR03EZPJ000"
			(at 372.11 220.98 0)
			(effects
				(font
					(size 1.27 1.27)
					(thickness 0.15)
				)
				(justify left bottom)
				(hide yes)
			)
		)
		(property "Manufacturer" "ROHM Semiconductor"
			(at 372.11 223.52 0)
			(effects
				(font
					(size 1.27 1.27)
					(thickness 0.15)
				)
				(justify left bottom)
				(hide yes)
			)
		)
		(property "Val" "0R"
			(at 382.27 208.28 0)
			(effects
				(font
					(size 1.27 1.27)
					(thickness 0.15)
				)
			)
		)
		(property "Max. Curr." "22.4A"
			(at 387.35 208.28 0)
			(effects
				(font
					(size 1.27 1.27)
					(thickness 0.15)
				)
			)
		)
		(property "Author" "Antmicro"
			(at 372.11 228.6 0)
			(effects
				(font
					(size 1.27 1.27)
					(thickness 0.15)
				)
				(justify left bottom)
				(hide yes)
			)
		)
		(property "License" "Apache-2.0"
			(at 372.11 231.14 0)
			(effects
				(font
					(size 1.27 1.27)
					(thickness 0.15)
				)
				(justify left bottom)
				(hide yes)
			)
		)
		(property "Tolerance" "template_tolerance"
			(at 367.03 215.9 0)
			(effects
				(font
					(size 1.27 1.27)
				)
				(justify left bottom)
				(hide yes)
			)
		)
		(pin "1"
		)
		(pin "2"
		)
		(instances
			(project "jetson-agx-thor-baseboard"
				(path ""
					(reference "R248")
					(unit 1)
				)
			)
		)
	)
	(symbol
		(lib_id "antmicropower:GND")
		(at 358.14 186.69 0)
		(unit 1)
		(exclude_from_sim no)
		(in_bom yes)
		(on_board yes)
		(dnp no)
		(fields_autoplaced yes)
		(property "Reference" "#PWR011"
			(at 358.14 193.04 0)
			(effects
				(font
					(size 1.27 1.27)
				)
				(justify left bottom)
				(hide yes)
			)
		)
		(property "Value" "GND"
			(at 358.14 190.5 0)
			(effects
				(font
					(size 1.27 1.27)
					(thickness 0.15)
				)
			)
		)
		(property "Footprint" ""
			(at 367.03 194.31 0)
			(effects
				(font
					(size 1.27 1.27)
					(thickness 0.15)
				)
				(justify left bottom)
				(hide yes)
			)
		)
		(property "Datasheet" ""
			(at 367.03 199.39 0)
			(effects
				(font
					(size 1.27 1.27)
					(thickness 0.15)
				)
				(justify left bottom)
				(hide yes)
			)
		)
		(property "Description" ""
			(at 358.14 186.69 0)
			(effects
				(font
					(size 1.27 1.27)
				)
				(hide yes)
			)
		)
		(property "Author" "Antmicro"
			(at 367.03 194.31 0)
			(effects
				(font
					(size 1.27 1.27)
					(thickness 0.15)
				)
				(justify left bottom)
				(hide yes)
			)
		)
		(property "License" "Apache-2.0"
			(at 367.03 196.85 0)
			(effects
				(font
					(size 1.27 1.27)
					(thickness 0.15)
				)
				(justify left bottom)
				(hide yes)
			)
		)
		(pin "1"
		)
		(instances
			(project "jetson-agx-thor-baseboard"
				(path ""
					(reference "#PWR011")
					(unit 1)
				)
			)
		)
	)
	(symbol
		(lib_id "antmicroB2BConnectors:ASP-208571-01_mounting_holes")
		(at 236.22 153.67 0)
		(mirror y)
		(unit 1)
		(exclude_from_sim no)
		(in_bom yes)
		(on_board yes)
		(dnp no)
		(fields_autoplaced yes)
		(property "Reference" "J18"
			(at 224.79 146.05 0)
			(effects
				(font
					(size 1.27 1.27)
					(thickness 0.15)
				)
			)
		)
		(property "Value" "ASP-208571-01_mounting_holes"
			(at 199.39 163.83 0)
			(effects
				(font
					(size 1.27 1.27)
					(thickness 0.15)
				)
				(justify left bottom)
				(hide yes)
			)
		)
		(property "Footprint" "antmicro-footprints:ASP-208571-01_mounting_holes"
			(at 199.39 166.37 0)
			(effects
				(font
					(size 1.27 1.27)
					(thickness 0.15)
				)
				(justify left bottom)
				(hide yes)
			)
		)
		(property "Datasheet" "https://suddendocs.samtec.com/prints/asp-208571-01-mkt.pdf"
			(at 199.39 168.91 0)
			(effects
				(font
					(size 1.27 1.27)
					(thickness 0.15)
				)
				(justify left bottom)
				(hide yes)
			)
		)
		(property "Description" "FMC connector"
			(at 199.39 179.07 0)
			(effects
				(font
					(size 1.27 1.27)
				)
				(justify left bottom)
				(hide yes)
			)
		)
		(property "MPN" "ASP-208571-01"
			(at 224.79 148.59 0)
			(effects
				(font
					(size 1.27 1.27)
					(thickness 0.15)
				)
			)
		)
		(property "Manufacturer" "Samtec"
			(at 199.39 171.45 0)
			(effects
				(font
					(size 1.27 1.27)
					(thickness 0.15)
				)
				(justify left bottom)
				(hide yes)
			)
		)
		(property "Author" "Antmicro"
			(at 199.39 173.99 0)
			(effects
				(font
					(size 1.27 1.27)
					(thickness 0.15)
				)
				(justify left bottom)
				(hide yes)
			)
		)
		(property "License" "Apache-2.0"
			(at 199.39 176.53 0)
			(effects
				(font
					(size 1.27 1.27)
					(thickness 0.15)
				)
				(justify left bottom)
				(hide yes)
			)
		)
		(pin "A40"
		)
		(pin "Z01"
		)
		(pin "A09"
		)
		(pin "Y28"
		)
		(pin "D27"
		)
		(pin "B33"
		)
		(pin "C25"
		)
		(pin "C20"
		)
		(pin "Z05"
		)
		(pin "A10"
		)
		(pin "B14"
		)
		(pin "Y39"
		)
		(pin "C36"
		)
		(pin "F14"
		)
		(pin "H02"
		)
		(pin "H03"
		)
		(pin "A28"
		)
		(pin "C37"
		)
		(pin "A26"
		)
		(pin "C19"
		)
		(pin "Z06"
		)
		(pin "C28"
		)
		(pin "B10"
		)
		(pin "Z27"
		)
		(pin "B40"
		)
		(pin "Z28"
		)
		(pin "Z26"
		)
		(pin "C24"
		)
		(pin "B09"
		)
		(pin "Y27"
		)
		(pin "C08"
		)
		(pin "Z04"
		)
		(pin "A36"
		)
		(pin "C02"
		)
		(pin "A19"
		)
		(pin "E34"
		)
		(pin "K28"
		)
		(pin "K29"
		)
		(pin "G20"
		)
		(pin "G21"
		)
		(pin "A08"
		)
		(pin "B27"
		)
		(pin "D22"
		)
		(pin "F25"
		)
		(pin "C30"
		)
		(pin "D04"
		)
		(pin "A30"
		)
		(pin "A38"
		)
		(pin "B37"
		)
		(pin "G26"
		)
		(pin "G27"
		)
		(pin "C03"
		)
		(pin "F07"
		)
		(pin "D34"
		)
		(pin "G08"
		)
		(pin "G18"
		)
		(pin "G19"
		)
		(pin "G01"
		)
		(pin "A20"
		)
		(pin "M04"
		)
		(pin "M05"
		)
		(pin "Y08"
		)
		(pin "F39"
		)
		(pin "F19"
		)
		(pin "K04"
		)
		(pin "K05"
		)
		(pin "G12"
		)
		(pin "G13"
		)
		(pin "Y02"
		)
		(pin "J32"
		)
		(pin "J33"
		)
		(pin "B11"
		)
		(pin "D07"
		)
		(pin "C33"
		)
		(pin "A17"
		)
		(pin "D14"
		)
		(pin "A15"
		)
		(pin "B39"
		)
		(pin "A18"
		)
		(pin "B21"
		)
		(pin "D11"
		)
		(pin "Y15"
		)
		(pin "B16"
		)
		(pin "Y09"
		)
		(pin "F29"
		)
		(pin "J30"
		)
		(pin "J31"
		)
		(pin "B19"
		)
		(pin "A05"
		)
		(pin "B38"
		)
		(pin "E22"
		)
		(pin "D15"
		)
		(pin "L02"
		)
		(pin "L03"
		)
		(pin "Y37"
		)
		(pin "E07"
		)
		(pin "A22"
		)
		(pin "H20"
		)
		(pin "H21"
		)
		(pin "Z39"
		)
		(pin "F37"
		)
		(pin "B30"
		)
		(pin "Z15"
		)
		(pin "H36"
		)
		(pin "H37"
		)
		(pin "D16"
		)
		(pin "D37"
		)
		(pin "C40"
		)
		(pin "E29"
		)
		(pin "Y36"
		)
		(pin "K10"
		)
		(pin "K11"
		)
		(pin "F38"
		)
		(pin "B04"
		)
		(pin "F15"
		)
		(pin "J28"
		)
		(pin "J29"
		)
		(pin "B17"
		)
		(pin "E37"
		)
		(pin "E09"
		)
		(pin "Z23"
		)
		(pin "J06"
		)
		(pin "J07"
		)
		(pin "Z30"
		)
		(pin "C31"
		)
		(pin "Z37"
		)
		(pin "Z33"
		)
		(pin "Z29"
		)
		(pin "Y26"
		)
		(pin "H06"
		)
		(pin "H07"
		)
		(pin "C10"
		)
		(pin "F27"
		)
		(pin "A03"
		)
		(pin "M10"
		)
		(pin "M11"
		)
		(pin "M12"
		)
		(pin "L04"
		)
		(pin "L05"
		)
		(pin "A24"
		)
		(pin "M28"
		)
		(pin "M29"
		)
		(pin "M30"
		)
		(pin "D32"
		)
		(pin "H18"
		)
		(pin "H19"
		)
		(pin "F03"
		)
		(pin "L08"
		)
		(pin "L09"
		)
		(pin "A01"
		)
		(pin "B32"
		)
		(pin "K36"
		)
		(pin "K37"
		)
		(pin "C01"
		)
		(pin "D18"
		)
		(pin "E12"
		)
		(pin "K16"
		)
		(pin "K17"
		)
		(pin "Y11"
		)
		(pin "B31"
		)
		(pin "D28"
		)
		(pin "D23"
		)
		(pin "Z18"
		)
		(pin "D17"
		)
		(pin "F32"
		)
		(pin "B20"
		)
		(pin "C18"
		)
		(pin "A25"
		)
		(pin "Y05"
		)
		(pin "J26"
		)
		(pin "J27"
		)
		(pin "Y33"
		)
		(pin "A37"
		)
		(pin "Z21"
		)
		(pin "D09"
		)
		(pin "B26"
		)
		(pin "A35"
		)
		(pin "D20"
		)
		(pin "A11"
		)
		(pin "C15"
		)
		(pin "G14"
		)
		(pin "G15"
		)
		(pin "D01"
		)
		(pin "D21"
		)
		(pin "M34"
		)
		(pin "M35"
		)
		(pin "M36"
		)
		(pin "L32"
		)
		(pin "L33"
		)
		(pin "D31"
		)
		(pin "Z07"
		)
		(pin "M31"
		)
		(pin "M32"
		)
		(pin "M33"
		)
		(pin "K18"
		)
		(pin "K19"
		)
		(pin "F06"
		)
		(pin "Z16"
		)
		(pin "H32"
		)
		(pin "H33"
		)
		(pin "Z36"
		)
		(pin "F05"
		)
		(pin "F02"
		)
		(pin "E05"
		)
		(pin "F40"
		)
		(pin "E39"
		)
		(pin "H08"
		)
		(pin "H09"
		)
		(pin "B02"
		)
		(pin "E16"
		)
		(pin "E38"
		)
		(pin "Z12"
		)
		(pin "A34"
		)
		(pin "K08"
		)
		(pin "K09"
		)
		(pin "E31"
		)
		(pin "Y06"
		)
		(pin "F11"
		)
		(pin "F08"
		)
		(pin "A32"
		)
		(pin "Y22"
		)
		(pin "H12"
		)
		(pin "H13"
		)
		(pin "A27"
		)
		(pin "C05"
		)
		(pin "K12"
		)
		(pin "K13"
		)
		(pin "L14"
		)
		(pin "L15"
		)
		(pin "E25"
		)
		(pin "L18"
		)
		(pin "L19"
		)
		(pin "M19"
		)
		(pin "M20"
		)
		(pin "M21"
		)
		(pin "J14"
		)
		(pin "J15"
		)
		(pin "G40"
		)
		(pin "H01"
		)
		(pin "Y25"
		)
		(pin "A33"
		)
		(pin "Z35"
		)
		(pin "H38"
		)
		(pin "H39"
		)
		(pin "D29"
		)
		(pin "E02"
		)
		(pin "D10"
		)
		(pin "C12"
		)
		(pin "C26"
		)
		(pin "M40"
		)
		(pin "B24"
		)
		(pin "Y24"
		)
		(pin "F33"
		)
		(pin "F21"
		)
		(pin "E20"
		)
		(pin "D06"
		)
		(pin "C29"
		)
		(pin "E23"
		)
		(pin "J04"
		)
		(pin "J05"
		)
		(pin "B28"
		)
		(pin "K30"
		)
		(pin "K31"
		)
		(pin "B08"
		)
		(pin "L12"
		)
		(pin "L13"
		)
		(pin "J38"
		)
		(pin "J39"
		)
		(pin "D24"
		)
		(pin "E06"
		)
		(pin "D35"
		)
		(pin "G07"
		)
		(pin "C39"
		)
		(pin "E04"
		)
		(pin "L34"
		)
		(pin "L35"
		)
		(pin "D02"
		)
		(pin "Z22"
		)
		(pin "K14"
		)
		(pin "K15"
		)
		(pin "Y34"
		)
		(pin "M08"
		)
		(pin "M09"
		)
		(pin "D30"
		)
		(pin "G10"
		)
		(pin "G11"
		)
		(pin "C11"
		)
		(pin "E33"
		)
		(pin "G38"
		)
		(pin "G39"
		)
		(pin "F34"
		)
		(pin "H04"
		)
		(pin "H05"
		)
		(pin "F09"
		)
		(pin "G22"
		)
		(pin "G23"
		)
		(pin "B34"
		)
		(pin "Z20"
		)
		(pin "Y03"
		)
		(pin "M06"
		)
		(pin "M07"
		)
		(pin "K38"
		)
		(pin "K39"
		)
		(pin "Y21"
		)
		(pin "K24"
		)
		(pin "K25"
		)
		(pin "E21"
		)
		(pin "L20"
		)
		(pin "L21"
		)
		(pin "E11"
		)
		(pin "K22"
		)
		(pin "K23"
		)
		(pin "B12"
		)
		(pin "J22"
		)
		(pin "J23"
		)
		(pin "A07"
		)
		(pin "E32"
		)
		(pin "L36"
		)
		(pin "L37"
		)
		(pin "L24"
		)
		(pin "L25"
		)
		(pin "Y32"
		)
		(pin "F13"
		)
		(pin "G09"
		)
		(pin "Y01"
		)
		(pin "K06"
		)
		(pin "K07"
		)
		(pin "G28"
		)
		(pin "G29"
		)
		(pin "K40"
		)
		(pin "L01"
		)
		(pin "J02"
		)
		(pin "J03"
		)
		(pin "J12"
		)
		(pin "J13"
		)
		(pin "M25"
		)
		(pin "M26"
		)
		(pin "M27"
		)
		(pin "A13"
		)
		(pin "F20"
		)
		(pin "M37"
		)
		(pin "M38"
		)
		(pin "M39"
		)
		(pin "Y10"
		)
		(pin "G32"
		)
		(pin "G33"
		)
		(pin "A29"
		)
		(pin "L10"
		)
		(pin "L11"
		)
		(pin "G24"
		)
		(pin "G25"
		)
		(pin "E08"
		)
		(pin "C06"
		)
		(pin "A12"
		)
		(pin "F12"
		)
		(pin "C16"
		)
		(pin "Z09"
		)
		(pin "E19"
		)
		(pin "D03"
		)
		(pin "E24"
		)
		(pin "F23"
		)
		(pin "G16"
		)
		(pin "G17"
		)
		(pin "A23"
		)
		(pin "D12"
		)
		(pin "C07"
		)
		(pin "L30"
		)
		(pin "L31"
		)
		(pin "B29"
		)
		(pin "B15"
		)
		(pin "J16"
		)
		(pin "J17"
		)
		(pin "K26"
		)
		(pin "K27"
		)
		(pin "A16"
		)
		(pin "E01"
		)
		(pin "Y12"
		)
		(pin "G04"
		)
		(pin "C32"
		)
		(pin "B22"
		)
		(pin "Y16"
		)
		(pin "G34"
		)
		(pin "G35"
		)
		(pin "A02"
		)
		(pin "D40"
		)
		(pin "Y38"
		)
		(pin "D08"
		)
		(pin "C27"
		)
		(pin "J36"
		)
		(pin "J37"
		)
		(pin "K34"
		)
		(pin "K35"
		)
		(pin "M02"
		)
		(pin "M03"
		)
		(pin "B01"
		)
		(pin "E35"
		)
		(pin "Y13"
		)
		(pin "L26"
		)
		(pin "L27"
		)
		(pin "G36"
		)
		(pin "G37"
		)
		(pin "K32"
		)
		(pin "K33"
		)
		(pin "Y14"
		)
		(pin "D13"
		)
		(pin "D25"
		)
		(pin "F10"
		)
		(pin "E10"
		)
		(pin "E26"
		)
		(pin "E18"
		)
		(pin "F24"
		)
		(pin "Z10"
		)
		(pin "H40"
		)
		(pin "J01"
		)
		(pin "G05"
		)
		(pin "Z17"
		)
		(pin "F22"
		)
		(pin "A14"
		)
		(pin "E30"
		)
		(pin "Z13"
		)
		(pin "H22"
		)
		(pin "H23"
		)
		(pin "E28"
		)
		(pin "F36"
		)
		(pin "B18"
		)
		(pin "Z08"
		)
		(pin "H34"
		)
		(pin "H35"
		)
		(pin "J08"
		)
		(pin "J09"
		)
		(pin "C23"
		)
		(pin "J40"
		)
		(pin "K01"
		)
		(pin "Y07"
		)
		(pin "H14"
		)
		(pin "H15"
		)
		(pin "D36"
		)
		(pin "Y35"
		)
		(pin "C13"
		)
		(pin "F30"
		)
		(pin "L40"
		)
		(pin "M01"
		)
		(pin "F17"
		)
		(pin "Z03"
		)
		(pin "F28"
		)
		(pin "Z40"
		)
		(pin "A39"
		)
		(pin "Y40"
		)
		(pin "M13"
		)
		(pin "M14"
		)
		(pin "M15"
		)
		(pin "D38"
		)
		(pin "Y29"
		)
		(pin "F18"
		)
		(pin "E40"
		)
		(pin "B36"
		)
		(pin "E15"
		)
		(pin "C09"
		)
		(pin "E27"
		)
		(pin "Z31"
		)
		(pin "A06"
		)
		(pin "L22"
		)
		(pin "L23"
		)
		(pin "C34"
		)
		(pin "Y19"
		)
		(pin "J18"
		)
		(pin "J19"
		)
		(pin "L38"
		)
		(pin "L39"
		)
		(pin "G03"
		)
		(pin "F01"
		)
		(pin "M16"
		)
		(pin "M17"
		)
		(pin "M18"
		)
		(pin "J20"
		)
		(pin "J21"
		)
		(pin "H26"
		)
		(pin "H27"
		)
		(pin "Y20"
		)
		(pin "H28"
		)
		(pin "H29"
		)
		(pin "Z34"
		)
		(pin "D26"
		)
		(pin "Y31"
		)
		(pin "G06"
		)
		(pin "Z11"
		)
		(pin "H30"
		)
		(pin "H31"
		)
		(pin "Y04"
		)
		(pin "Z24"
		)
		(pin "D33"
		)
		(pin "F35"
		)
		(pin "B35"
		)
		(pin "B06"
		)
		(pin "B23"
		)
		(pin "M22"
		)
		(pin "M23"
		)
		(pin "M24"
		)
		(pin "Y30"
		)
		(pin "B07"
		)
		(pin "C21"
		)
		(pin "H16"
		)
		(pin "H17"
		)
		(pin "H24"
		)
		(pin "H25"
		)
		(pin "C04"
		)
		(pin "A31"
		)
		(pin "A04"
		)
		(pin "E14"
		)
		(pin "Z38"
		)
		(pin "E17"
		)
		(pin "A21"
		)
		(pin "B03"
		)
		(pin "F04"
		)
		(pin "B13"
		)
		(pin "C14"
		)
		(pin "Z19"
		)
		(pin "Y18"
		)
		(pin "Z14"
		)
		(pin "Z25"
		)
		(pin "J24"
		)
		(pin "J25"
		)
		(pin "H10"
		)
		(pin "H11"
		)
		(pin "K20"
		)
		(pin "K21"
		)
		(pin "F31"
		)
		(pin "F16"
		)
		(pin "E13"
		)
		(pin "F26"
		)
		(pin "C22"
		)
		(pin "E36"
		)
		(pin "J34"
		)
		(pin "J35"
		)
		(pin "C35"
		)
		(pin "L16"
		)
		(pin "L17"
		)
		(pin "J10"
		)
		(pin "J11"
		)
		(pin "L06"
		)
		(pin "L07"
		)
		(pin "D19"
		)
		(pin "Z02"
		)
		(pin "D39"
		)
		(pin "Z32"
		)
		(pin "B25"
		)
		(pin "B05"
		)
		(pin "G30"
		)
		(pin "G31"
		)
		(pin "K02"
		)
		(pin "K03"
		)
		(pin "E03"
		)
		(pin "C38"
		)
		(pin "C17"
		)
		(pin "G02"
		)
		(pin "Y23"
		)
		(pin "D05"
		)
		(pin "L28"
		)
		(pin "L29"
		)
		(pin "Y17"
		)
		(instances
			(project "jetson-agx-thor-baseboard"
				(path ""
					(reference "J18")
					(unit 1)
				)
			)
		)
	)
	(symbol
		(lib_id "antmicroTestPoints:TP_0.75mm_SMD")
		(at 83.82 232.41 0)
		(unit 1)
		(exclude_from_sim no)
		(in_bom no)
		(on_board yes)
		(dnp no)
		(property "Reference" "TP114"
			(at 88.138 232.41 0)
			(effects
				(font
					(size 1.27 1.27)
					(thickness 0.15)
				)
				(justify left)
			)
		)
		(property "Value" "TP_0.75mm_SMD"
			(at 93.98 236.22 0)
			(effects
				(font
					(size 1.27 1.27)
					(thickness 0.15)
				)
				(justify left bottom)
				(hide yes)
			)
		)
		(property "Footprint" "antmicro-footprints:TP_SMD_0.75mm"
			(at 93.98 238.76 0)
			(effects
				(font
					(size 1.27 1.27)
					(thickness 0.15)
				)
				(justify left bottom)
				(hide yes)
			)
		)
		(property "Datasheet" ""
			(at 101.6 245.11 0)
			(effects
				(font
					(size 1.27 1.27)
					(thickness 0.15)
				)
				(justify left bottom)
				(hide yes)
			)
		)
		(property "Description" "SMT test point"
			(at 94.615 246.38 0)
			(effects
				(font
					(size 1.27 1.27)
				)
				(justify left bottom)
				(hide yes)
			)
		)
		(property "MPN" ""
			(at 94.615 243.84 0)
			(effects
				(font
					(size 1.27 1.27)
					(thickness 0.15)
				)
				(justify left bottom)
				(hide yes)
			)
		)
		(property "Manufacturer" ""
			(at 94.615 238.76 0)
			(effects
				(font
					(size 1.27 1.27)
					(thickness 0.15)
				)
				(justify left bottom)
				(hide yes)
			)
		)
		(property "Author" "Antmicro"
			(at 93.98 241.3 0)
			(effects
				(font
					(size 1.27 1.27)
					(thickness 0.15)
				)
				(justify left bottom)
				(hide yes)
			)
		)
		(property "License" "Apache-2.0"
			(at 93.98 243.84 0)
			(effects
				(font
					(size 1.27 1.27)
					(thickness 0.15)
				)
				(justify left bottom)
				(hide yes)
			)
		)
		(pin "1"
		)
		(instances
			(project "jetson-agx-thor-baseboard"
				(path ""
					(reference "TP114")
					(unit 1)
				)
			)
		)
	)
	(symbol
		(lib_id "antmicropower:GND")
		(at 393.7 187.96 0)
		(unit 1)
		(exclude_from_sim no)
		(in_bom yes)
		(on_board yes)
		(dnp no)
		(fields_autoplaced yes)
		(property "Reference" "#PWR09"
			(at 393.7 194.31 0)
			(effects
				(font
					(size 1.27 1.27)
				)
				(justify left bottom)
				(hide yes)
			)
		)
		(property "Value" "GND"
			(at 393.7 191.77 0)
			(effects
				(font
					(size 1.27 1.27)
					(thickness 0.15)
				)
			)
		)
		(property "Footprint" ""
			(at 402.59 195.58 0)
			(effects
				(font
					(size 1.27 1.27)
					(thickness 0.15)
				)
				(justify left bottom)
				(hide yes)
			)
		)
		(property "Datasheet" ""
			(at 402.59 200.66 0)
			(effects
				(font
					(size 1.27 1.27)
					(thickness 0.15)
				)
				(justify left bottom)
				(hide yes)
			)
		)
		(property "Description" ""
			(at 393.7 187.96 0)
			(effects
				(font
					(size 1.27 1.27)
				)
				(hide yes)
			)
		)
		(property "Author" "Antmicro"
			(at 402.59 195.58 0)
			(effects
				(font
					(size 1.27 1.27)
					(thickness 0.15)
				)
				(justify left bottom)
				(hide yes)
			)
		)
		(property "License" "Apache-2.0"
			(at 402.59 198.12 0)
			(effects
				(font
					(size 1.27 1.27)
					(thickness 0.15)
				)
				(justify left bottom)
				(hide yes)
			)
		)
		(pin "1"
		)
		(instances
			(project "jetson-agx-thor-baseboard"
				(path ""
					(reference "#PWR09")
					(unit 1)
				)
			)
		)
	)
	(symbol
		(lib_id "antmicroResistors0402:R_0R_0402")
		(at 193.04 224.79 0)
		(mirror x)
		(unit 1)
		(exclude_from_sim no)
		(in_bom yes)
		(on_board yes)
		(dnp no)
		(property "Reference" "R351"
			(at 195.58 229.235 0)
			(effects
				(font
					(size 1.27 1.27)
					(thickness 0.15)
				)
			)
		)
		(property "Value" "R_0R_0402"
			(at 213.36 212.09 0)
			(effects
				(font
					(size 1.27 1.27)
					(thickness 0.15)
				)
				(justify left bottom)
				(hide yes)
			)
		)
		(property "Footprint" "antmicro-footprints:R_0402_1005Metric"
			(at 213.36 209.55 0)
			(effects
				(font
					(size 1.27 1.27)
					(thickness 0.15)
				)
				(justify left bottom)
				(hide yes)
			)
		)
		(property "Datasheet" "https://industrial.panasonic.com/cdbs/www-data/pdf/RDA0000/AOA0000C301.pdf"
			(at 213.36 207.01 0)
			(effects
				(font
					(size 1.27 1.27)
					(thickness 0.15)
				)
				(justify left bottom)
				(hide yes)
			)
		)
		(property "Description" "SMD Chip Resistor, Jumper, 0 ohm, 100 mW, 0402 [1005 Metric], Thick Film, General Purpose"
			(at 213.36 191.77 0)
			(effects
				(font
					(size 1.27 1.27)
				)
				(justify left bottom)
				(hide yes)
			)
		)
		(property "MPN" "ERJ2GE0R00X"
			(at 213.36 204.47 0)
			(effects
				(font
					(size 1.27 1.27)
					(thickness 0.15)
				)
				(justify left bottom)
				(hide yes)
			)
		)
		(property "Manufacturer" "Panasonic"
			(at 213.36 201.93 0)
			(effects
				(font
					(size 1.27 1.27)
					(thickness 0.15)
				)
				(justify left bottom)
				(hide yes)
			)
		)
		(property "License" "Apache-2.0"
			(at 213.36 199.39 0)
			(effects
				(font
					(size 1.27 1.27)
					(thickness 0.15)
				)
				(justify left bottom)
				(hide yes)
			)
		)
		(property "Author" "Antmicro"
			(at 213.36 196.85 0)
			(effects
				(font
					(size 1.27 1.27)
					(thickness 0.15)
				)
				(justify left bottom)
				(hide yes)
			)
		)
		(property "Val" "0R"
			(at 195.58 227.33 0)
			(effects
				(font
					(size 1.27 1.27)
					(thickness 0.15)
				)
			)
		)
		(property "Tolerance" "~"
			(at 213.36 214.63 0)
			(effects
				(font
					(size 1.27 1.27)
				)
				(justify left bottom)
				(hide yes)
			)
		)
		(property "Current" "1A"
			(at 213.36 194.31 0)
			(effects
				(font
					(size 1.27 1.27)
					(thickness 0.15)
				)
				(justify left bottom)
				(hide yes)
			)
		)
		(pin "2"
		)
		(pin "1"
		)
		(instances
			(project "jetson-agx-thor-baseboard"
				(path ""
					(reference "R351")
					(unit 1)
				)
			)
		)
	)
	(symbol
		(lib_id "antmicropower:+1V8")
		(at 379.73 224.79 0)
		(unit 1)
		(exclude_from_sim no)
		(in_bom yes)
		(on_board yes)
		(dnp no)
		(property "Reference" "#PWR0441"
			(at 379.73 228.6 0)
			(effects
				(font
					(size 1.27 1.27)
				)
				(justify left bottom)
				(hide yes)
			)
		)
		(property "Value" "+5V"
			(at 376.555 220.98 0)
			(effects
				(font
					(size 1.27 1.27)
					(thickness 0.15)
				)
				(justify left)
			)
		)
		(property "Footprint" ""
			(at 394.97 232.41 0)
			(effects
				(font
					(size 1.27 1.27)
					(thickness 0.15)
				)
				(justify left bottom)
				(hide yes)
			)
		)
		(property "Datasheet" ""
			(at 394.97 234.95 0)
			(effects
				(font
					(size 1.27 1.27)
					(thickness 0.15)
				)
				(justify left bottom)
				(hide yes)
			)
		)
		(property "Description" ""
			(at 379.73 224.79 0)
			(effects
				(font
					(size 1.27 1.27)
				)
				(hide yes)
			)
		)
		(property "Author" "Antmicro"
			(at 394.97 229.87 0)
			(effects
				(font
					(size 1.27 1.27)
					(thickness 0.15)
				)
				(justify left bottom)
				(hide yes)
			)
		)
		(property "License" "Apache-2.0"
			(at 394.97 232.41 0)
			(effects
				(font
					(size 1.27 1.27)
					(thickness 0.15)
				)
				(justify left bottom)
				(hide yes)
			)
		)
		(pin "1"
		)
		(instances
			(project "jetson-agx-thor-baseboard"
				(path ""
					(reference "#PWR0441")
					(unit 1)
				)
			)
		)
	)
	(symbol
		(lib_id "antmicroResistors0402:R_10k_0402")
		(at 384.81 185.42 0)
		(unit 1)
		(exclude_from_sim no)
		(in_bom no)
		(on_board yes)
		(dnp yes)
		(property "Reference" "R348"
			(at 385.064 183.388 0)
			(effects
				(font
					(size 1.27 1.27)
					(thickness 0.15)
				)
			)
		)
		(property "Value" "R_10k_0402"
			(at 405.13 198.12 0)
			(effects
				(font
					(size 1.27 1.27)
					(thickness 0.15)
				)
				(justify left bottom)
				(hide yes)
			)
		)
		(property "Footprint" "antmicro-footprints:R_0402_1005Metric"
			(at 405.13 200.66 0)
			(effects
				(font
					(size 1.27 1.27)
					(thickness 0.15)
				)
				(justify left bottom)
				(hide yes)
			)
		)
		(property "Datasheet" "https://www.bourns.com/docs/product-datasheets/cr.pdf"
			(at 405.13 203.2 0)
			(effects
				(font
					(size 1.27 1.27)
					(thickness 0.15)
				)
				(justify left bottom)
				(hide yes)
			)
		)
		(property "Description" "SMD Chip Resistor, 10 kohm, ± 1%, 62.5 mW, 0402 [1005 Metric], Thick Film, General Purpose"
			(at 405.13 215.9 0)
			(effects
				(font
					(size 1.27 1.27)
				)
				(justify left bottom)
				(hide yes)
			)
		)
		(property "MPN" "CR0402-FX-1002GLF"
			(at 405.13 205.74 0)
			(effects
				(font
					(size 1.27 1.27)
					(thickness 0.15)
				)
				(justify left bottom)
				(hide yes)
			)
		)
		(property "Manufacturer" "Bourns"
			(at 405.13 208.28 0)
			(effects
				(font
					(size 1.27 1.27)
					(thickness 0.15)
				)
				(justify left bottom)
				(hide yes)
			)
		)
		(property "License" "Apache-2.0"
			(at 405.13 210.82 0)
			(effects
				(font
					(size 1.27 1.27)
					(thickness 0.15)
				)
				(justify left bottom)
				(hide yes)
			)
		)
		(property "Author" "Antmicro"
			(at 405.13 213.36 0)
			(effects
				(font
					(size 1.27 1.27)
					(thickness 0.15)
				)
				(justify left bottom)
				(hide yes)
			)
		)
		(property "Val" "10k"
			(at 391.16 183.388 0)
			(effects
				(font
					(size 1.27 1.27)
					(thickness 0.15)
				)
			)
		)
		(property "Tolerance" "1%"
			(at 405.13 195.58 0)
			(effects
				(font
					(size 1.27 1.27)
				)
				(justify left bottom)
				(hide yes)
			)
		)
		(pin "1"
		)
		(pin "2"
		)
		(instances
			(project "jetson-agx-thor-baseboard"
				(path ""
					(reference "R348")
					(unit 1)
				)
			)
		)
	)
	(symbol
		(lib_id "antmicroResistors0402:R_10k_0402")
		(at 384.81 180.34 0)
		(unit 1)
		(exclude_from_sim no)
		(in_bom no)
		(on_board yes)
		(dnp yes)
		(property "Reference" "R340"
			(at 385.064 178.308 0)
			(effects
				(font
					(size 1.27 1.27)
					(thickness 0.15)
				)
			)
		)
		(property "Value" "R_10k_0402"
			(at 405.13 193.04 0)
			(effects
				(font
					(size 1.27 1.27)
					(thickness 0.15)
				)
				(justify left bottom)
				(hide yes)
			)
		)
		(property "Footprint" "antmicro-footprints:R_0402_1005Metric"
			(at 405.13 195.58 0)
			(effects
				(font
					(size 1.27 1.27)
					(thickness 0.15)
				)
				(justify left bottom)
				(hide yes)
			)
		)
		(property "Datasheet" "https://www.bourns.com/docs/product-datasheets/cr.pdf"
			(at 405.13 198.12 0)
			(effects
				(font
					(size 1.27 1.27)
					(thickness 0.15)
				)
				(justify left bottom)
				(hide yes)
			)
		)
		(property "Description" "SMD Chip Resistor, 10 kohm, ± 1%, 62.5 mW, 0402 [1005 Metric], Thick Film, General Purpose"
			(at 405.13 210.82 0)
			(effects
				(font
					(size 1.27 1.27)
				)
				(justify left bottom)
				(hide yes)
			)
		)
		(property "MPN" "CR0402-FX-1002GLF"
			(at 405.13 200.66 0)
			(effects
				(font
					(size 1.27 1.27)
					(thickness 0.15)
				)
				(justify left bottom)
				(hide yes)
			)
		)
		(property "Manufacturer" "Bourns"
			(at 405.13 203.2 0)
			(effects
				(font
					(size 1.27 1.27)
					(thickness 0.15)
				)
				(justify left bottom)
				(hide yes)
			)
		)
		(property "License" "Apache-2.0"
			(at 405.13 205.74 0)
			(effects
				(font
					(size 1.27 1.27)
					(thickness 0.15)
				)
				(justify left bottom)
				(hide yes)
			)
		)
		(property "Author" "Antmicro"
			(at 405.13 208.28 0)
			(effects
				(font
					(size 1.27 1.27)
					(thickness 0.15)
				)
				(justify left bottom)
				(hide yes)
			)
		)
		(property "Val" "10k"
			(at 391.16 178.308 0)
			(effects
				(font
					(size 1.27 1.27)
					(thickness 0.15)
				)
			)
		)
		(property "Tolerance" "1%"
			(at 405.13 190.5 0)
			(effects
				(font
					(size 1.27 1.27)
				)
				(justify left bottom)
				(hide yes)
			)
		)
		(pin "1"
		)
		(pin "2"
		)
		(instances
			(project ""
				(path ""
					(reference "R340")
					(unit 1)
				)
			)
		)
	)
	(symbol
		(lib_id "antmicroCapacitors0402:C_220n_0402")
		(at 269.24 247.65 0)
		(mirror y)
		(unit 1)
		(exclude_from_sim no)
		(in_bom yes)
		(on_board yes)
		(dnp no)
		(fields_autoplaced yes)
		(property "Reference" "C212"
			(at 270.256 246.38 0)
			(effects
				(font
					(size 1.27 1.27)
					(thickness 0.15)
				)
			)
		)
		(property "Value" "C_220n_0402"
			(at 254 270.51 0)
			(effects
				(font
					(size 1.27 1.27)
					(thickness 0.15)
				)
				(justify left bottom)
				(hide yes)
			)
		)
		(property "Footprint" "antmicro-footprints:C_0402_1005Metric"
			(at 254 273.05 0)
			(effects
				(font
					(size 1.27 1.27)
					(thickness 0.15)
				)
				(justify left bottom)
				(hide yes)
			)
		)
		(property "Datasheet" "https://www.yageo.com/en/Chart/Download/pdf/CC0402KRX5R6BB224"
			(at 254 275.59 0)
			(effects
				(font
					(size 1.27 1.27)
					(thickness 0.15)
				)
				(justify left bottom)
				(hide yes)
			)
		)
		(property "Description" "SMD Multilayer Ceramic Capacitor, 0.22 µF, 10 V, 0402 [1005 Metric], ± 10%, X5R, CC Series"
			(at 269.24 247.65 0)
			(effects
				(font
					(size 1.27 1.27)
				)
				(hide yes)
			)
		)
		(property "MPN" "CC0402KRX5R6BB224"
			(at 254 278.13 0)
			(effects
				(font
					(size 1.27 1.27)
					(thickness 0.15)
				)
				(justify left bottom)
				(hide yes)
			)
		)
		(property "Val" "220n"
			(at 262.89 246.38 0)
			(effects
				(font
					(size 1.27 1.27)
					(thickness 0.15)
				)
			)
		)
		(property "Voltage" "25V"
			(at 254 257.81 0)
			(effects
				(font
					(size 1.27 1.27)
					(thickness 0.15)
				)
				(justify left bottom)
				(hide yes)
			)
		)
		(property "Dielectric" "X7R"
			(at 254 260.35 0)
			(effects
				(font
					(size 1.27 1.27)
					(thickness 0.15)
				)
				(justify left bottom)
				(hide yes)
			)
		)
		(property "Manufacturer" "YAGEO"
			(at 254 262.89 0)
			(effects
				(font
					(size 1.27 1.27)
					(thickness 0.15)
				)
				(justify left bottom)
				(hide yes)
			)
		)
		(property "License" "Apache-2.0"
			(at 254 265.43 0)
			(effects
				(font
					(size 1.27 1.27)
					(thickness 0.15)
				)
				(justify left bottom)
				(hide yes)
			)
		)
		(property "Author" "Antmicro"
			(at 254 267.97 0)
			(effects
				(font
					(size 1.27 1.27)
					(thickness 0.15)
				)
				(justify left bottom)
				(hide yes)
			)
		)
		(property "Public" "False"
			(at 248.92 280.67 0)
			(effects
				(font
					(size 1.27 1.27)
				)
				(justify left bottom)
				(hide yes)
			)
		)
		(pin "2"
		)
		(pin "1"
		)
		(instances
			(project "jetson-agx-thor-baseboard"
				(path ""
					(reference "C212")
					(unit 1)
				)
			)
		)
	)
	(symbol
		(lib_id "antmicroCapacitorsmisc:C_22u_25V_0805")
		(at 358.14 234.95 270)
		(mirror x)
		(unit 1)
		(exclude_from_sim no)
		(in_bom yes)
		(on_board yes)
		(dnp no)
		(property "Reference" "C230"
			(at 355.6 229.8636 90)
			(effects
				(font
					(size 1.27 1.27)
					(thickness 0.15)
				)
				(justify right)
			)
		)
		(property "Value" "C_22u_25V_0805"
			(at 335.28 219.71 0)
			(effects
				(font
					(size 1.27 1.27)
					(thickness 0.15)
				)
				(justify left bottom)
				(hide yes)
			)
		)
		(property "Footprint" "antmicro-footprints:C_0805_2012Metric"
			(at 332.74 219.71 0)
			(effects
				(font
					(size 1.27 1.27)
					(thickness 0.15)
				)
				(justify left bottom)
				(hide yes)
			)
		)
		(property "Datasheet" "https://product.samsungsem.com/mlcc/CL21A226MAYNNN.do"
			(at 330.2 219.71 0)
			(effects
				(font
					(size 1.27 1.27)
					(thickness 0.15)
				)
				(justify left bottom)
				(hide yes)
			)
		)
		(property "Description" "SMT Multilayer Ceramic Capacitor, 22uF, +/-20%, 25V, X5R, 0805 [2012 Metric]"
			(at 358.14 234.95 0)
			(effects
				(font
					(size 1.27 1.27)
				)
				(hide yes)
			)
		)
		(property "MPN" "CL21A226MAYNNNE"
			(at 327.66 219.71 0)
			(effects
				(font
					(size 1.27 1.27)
					(thickness 0.15)
				)
				(justify left bottom)
				(hide yes)
			)
		)
		(property "Val" "22u"
			(at 355.6 232.4036 90)
			(effects
				(font
					(size 1.27 1.27)
					(thickness 0.15)
				)
				(justify right)
			)
		)
		(property "Voltage" "25V"
			(at 355.6 234.9436 90)
			(effects
				(font
					(size 1.27 1.27)
					(thickness 0.15)
				)
				(justify right)
			)
		)
		(property "Dielectric" "X5R"
			(at 345.44 219.71 0)
			(effects
				(font
					(size 1.27 1.27)
					(thickness 0.15)
				)
				(justify left bottom)
				(hide yes)
			)
		)
		(property "Manufacturer" "Samsung Electro-Mechanics"
			(at 342.9 219.71 0)
			(effects
				(font
					(size 1.27 1.27)
					(thickness 0.15)
				)
				(justify left bottom)
				(hide yes)
			)
		)
		(property "License" "Apache-2.0"
			(at 340.36 219.71 0)
			(effects
				(font
					(size 1.27 1.27)
					(thickness 0.15)
				)
				(justify left bottom)
				(hide yes)
			)
		)
		(property "Author" "Antmicro"
			(at 337.82 219.71 0)
			(effects
				(font
					(size 1.27 1.27)
					(thickness 0.15)
				)
				(justify left bottom)
				(hide yes)
			)
		)
		(property "Public" "False"
			(at 325.12 214.63 0)
			(effects
				(font
					(size 1.27 1.27)
				)
				(justify left bottom)
				(hide yes)
			)
		)
		(pin "2"
		)
		(pin "1"
		)
		(instances
			(project "jetson-agx-thor-baseboard"
				(path ""
					(reference "C230")
					(unit 1)
				)
			)
		)
	)
	(symbol
		(lib_id "antmicroResistors0402:R_10k_0402")
		(at 190.5 153.67 0)
		(mirror y)
		(unit 1)
		(exclude_from_sim no)
		(in_bom no)
		(on_board yes)
		(dnp yes)
		(property "Reference" "R275"
			(at 190.246 151.638 0)
			(effects
				(font
					(size 1.27 1.27)
					(thickness 0.15)
				)
			)
		)
		(property "Value" "R_10k_0402"
			(at 170.18 166.37 0)
			(effects
				(font
					(size 1.27 1.27)
					(thickness 0.15)
				)
				(justify left bottom)
				(hide yes)
			)
		)
		(property "Footprint" "antmicro-footprints:R_0402_1005Metric"
			(at 170.18 168.91 0)
			(effects
				(font
					(size 1.27 1.27)
					(thickness 0.15)
				)
				(justify left bottom)
				(hide yes)
			)
		)
		(property "Datasheet" "https://www.bourns.com/docs/product-datasheets/cr.pdf"
			(at 170.18 171.45 0)
			(effects
				(font
					(size 1.27 1.27)
					(thickness 0.15)
				)
				(justify left bottom)
				(hide yes)
			)
		)
		(property "Description" "SMD Chip Resistor, 10 kohm, ± 1%, 62.5 mW, 0402 [1005 Metric], Thick Film, General Purpose"
			(at 170.18 184.15 0)
			(effects
				(font
					(size 1.27 1.27)
				)
				(justify left bottom)
				(hide yes)
			)
		)
		(property "MPN" "CR0402-FX-1002GLF"
			(at 170.18 173.99 0)
			(effects
				(font
					(size 1.27 1.27)
					(thickness 0.15)
				)
				(justify left bottom)
				(hide yes)
			)
		)
		(property "Manufacturer" "Bourns"
			(at 170.18 176.53 0)
			(effects
				(font
					(size 1.27 1.27)
					(thickness 0.15)
				)
				(justify left bottom)
				(hide yes)
			)
		)
		(property "License" "Apache-2.0"
			(at 170.18 179.07 0)
			(effects
				(font
					(size 1.27 1.27)
					(thickness 0.15)
				)
				(justify left bottom)
				(hide yes)
			)
		)
		(property "Author" "Antmicro"
			(at 170.18 181.61 0)
			(effects
				(font
					(size 1.27 1.27)
					(thickness 0.15)
				)
				(justify left bottom)
				(hide yes)
			)
		)
		(property "Val" "10k"
			(at 184.15 151.638 0)
			(effects
				(font
					(size 1.27 1.27)
					(thickness 0.15)
				)
			)
		)
		(property "Tolerance" "1%"
			(at 170.18 163.83 0)
			(effects
				(font
					(size 1.27 1.27)
				)
				(justify left bottom)
				(hide yes)
			)
		)
		(pin "1"
		)
		(pin "2"
		)
		(instances
			(project "jetson-agx-thor-baseboard"
				(path ""
					(reference "R275")
					(unit 1)
				)
			)
		)
	)
	(symbol
		(lib_id "antmicroCapacitors0402:C_220n_0402")
		(at 261.62 250.19 0)
		(mirror y)
		(unit 1)
		(exclude_from_sim no)
		(in_bom yes)
		(on_board yes)
		(dnp no)
		(fields_autoplaced yes)
		(property "Reference" "C220"
			(at 262.636 248.92 0)
			(effects
				(font
					(size 1.27 1.27)
					(thickness 0.15)
				)
			)
		)
		(property "Value" "C_220n_0402"
			(at 246.38 273.05 0)
			(effects
				(font
					(size 1.27 1.27)
					(thickness 0.15)
				)
				(justify left bottom)
				(hide yes)
			)
		)
		(property "Footprint" "antmicro-footprints:C_0402_1005Metric"
			(at 246.38 275.59 0)
			(effects
				(font
					(size 1.27 1.27)
					(thickness 0.15)
				)
				(justify left bottom)
				(hide yes)
			)
		)
		(property "Datasheet" "https://www.yageo.com/en/Chart/Download/pdf/CC0402KRX5R6BB224"
			(at 246.38 278.13 0)
			(effects
				(font
					(size 1.27 1.27)
					(thickness 0.15)
				)
				(justify left bottom)
				(hide yes)
			)
		)
		(property "Description" "SMD Multilayer Ceramic Capacitor, 0.22 µF, 10 V, 0402 [1005 Metric], ± 10%, X5R, CC Series"
			(at 261.62 250.19 0)
			(effects
				(font
					(size 1.27 1.27)
				)
				(hide yes)
			)
		)
		(property "MPN" "CC0402KRX5R6BB224"
			(at 246.38 280.67 0)
			(effects
				(font
					(size 1.27 1.27)
					(thickness 0.15)
				)
				(justify left bottom)
				(hide yes)
			)
		)
		(property "Val" "220n"
			(at 255.27 248.92 0)
			(effects
				(font
					(size 1.27 1.27)
					(thickness 0.15)
				)
			)
		)
		(property "Voltage" "25V"
			(at 246.38 260.35 0)
			(effects
				(font
					(size 1.27 1.27)
					(thickness 0.15)
				)
				(justify left bottom)
				(hide yes)
			)
		)
		(property "Dielectric" "X7R"
			(at 246.38 262.89 0)
			(effects
				(font
					(size 1.27 1.27)
					(thickness 0.15)
				)
				(justify left bottom)
				(hide yes)
			)
		)
		(property "Manufacturer" "YAGEO"
			(at 246.38 265.43 0)
			(effects
				(font
					(size 1.27 1.27)
					(thickness 0.15)
				)
				(justify left bottom)
				(hide yes)
			)
		)
		(property "License" "Apache-2.0"
			(at 246.38 267.97 0)
			(effects
				(font
					(size 1.27 1.27)
					(thickness 0.15)
				)
				(justify left bottom)
				(hide yes)
			)
		)
		(property "Author" "Antmicro"
			(at 246.38 270.51 0)
			(effects
				(font
					(size 1.27 1.27)
					(thickness 0.15)
				)
				(justify left bottom)
				(hide yes)
			)
		)
		(property "Public" "False"
			(at 241.3 283.21 0)
			(effects
				(font
					(size 1.27 1.27)
				)
				(justify left bottom)
				(hide yes)
			)
		)
		(pin "2"
		)
		(pin "1"
		)
		(instances
			(project "jetson-agx-thor-baseboard"
				(path ""
					(reference "C220")
					(unit 1)
				)
			)
		)
	)
	(symbol
		(lib_id "antmicroResistors0402:R_10k_0402")
		(at 190.5 157.48 0)
		(mirror y)
		(unit 1)
		(exclude_from_sim no)
		(in_bom yes)
		(on_board yes)
		(dnp no)
		(property "Reference" "R319"
			(at 190.5 159.512 0)
			(effects
				(font
					(size 1.27 1.27)
					(thickness 0.15)
				)
			)
		)
		(property "Value" "R_10k_0402"
			(at 170.18 170.18 0)
			(effects
				(font
					(size 1.27 1.27)
					(thickness 0.15)
				)
				(justify left bottom)
				(hide yes)
			)
		)
		(property "Footprint" "antmicro-footprints:R_0402_1005Metric"
			(at 170.18 172.72 0)
			(effects
				(font
					(size 1.27 1.27)
					(thickness 0.15)
				)
				(justify left bottom)
				(hide yes)
			)
		)
		(property "Datasheet" "https://www.bourns.com/docs/product-datasheets/cr.pdf"
			(at 170.18 175.26 0)
			(effects
				(font
					(size 1.27 1.27)
					(thickness 0.15)
				)
				(justify left bottom)
				(hide yes)
			)
		)
		(property "Description" "SMD Chip Resistor, 10 kohm, ± 1%, 62.5 mW, 0402 [1005 Metric], Thick Film, General Purpose"
			(at 170.18 187.96 0)
			(effects
				(font
					(size 1.27 1.27)
				)
				(justify left bottom)
				(hide yes)
			)
		)
		(property "MPN" "CR0402-FX-1002GLF"
			(at 170.18 177.8 0)
			(effects
				(font
					(size 1.27 1.27)
					(thickness 0.15)
				)
				(justify left bottom)
				(hide yes)
			)
		)
		(property "Manufacturer" "Bourns"
			(at 170.18 180.34 0)
			(effects
				(font
					(size 1.27 1.27)
					(thickness 0.15)
				)
				(justify left bottom)
				(hide yes)
			)
		)
		(property "License" "Apache-2.0"
			(at 170.18 182.88 0)
			(effects
				(font
					(size 1.27 1.27)
					(thickness 0.15)
				)
				(justify left bottom)
				(hide yes)
			)
		)
		(property "Author" "Antmicro"
			(at 170.18 185.42 0)
			(effects
				(font
					(size 1.27 1.27)
					(thickness 0.15)
				)
				(justify left bottom)
				(hide yes)
			)
		)
		(property "Val" "10k"
			(at 184.404 159.512 0)
			(effects
				(font
					(size 1.27 1.27)
					(thickness 0.15)
				)
			)
		)
		(property "Tolerance" "1%"
			(at 170.18 167.64 0)
			(effects
				(font
					(size 1.27 1.27)
				)
				(justify left bottom)
				(hide yes)
			)
		)
		(pin "1"
		)
		(pin "2"
		)
		(instances
			(project "jetson-agx-thor-baseboard"
				(path ""
					(reference "R319")
					(unit 1)
				)
			)
		)
	)
	(symbol
		(lib_id "antmicropower:GND")
		(at 354.33 129.54 0)
		(unit 1)
		(exclude_from_sim no)
		(in_bom yes)
		(on_board yes)
		(dnp no)
		(fields_autoplaced yes)
		(property "Reference" "#PWR0428"
			(at 363.22 132.08 0)
			(effects
				(font
					(size 1.27 1.27)
					(thickness 0.15)
				)
				(justify left bottom)
				(hide yes)
			)
		)
		(property "Value" "GND"
			(at 354.33 134.62 0)
			(effects
				(font
					(size 1.27 1.27)
					(thickness 0.15)
				)
			)
		)
		(property "Footprint" ""
			(at 363.22 137.16 0)
			(effects
				(font
					(size 1.27 1.27)
					(thickness 0.15)
				)
				(justify left bottom)
				(hide yes)
			)
		)
		(property "Datasheet" ""
			(at 363.22 142.24 0)
			(effects
				(font
					(size 1.27 1.27)
					(thickness 0.15)
				)
				(justify left bottom)
				(hide yes)
			)
		)
		(property "Description" ""
			(at 354.33 129.54 0)
			(effects
				(font
					(size 1.27 1.27)
				)
				(hide yes)
			)
		)
		(property "Author" "Antmicro"
			(at 363.22 137.16 0)
			(effects
				(font
					(size 1.27 1.27)
					(thickness 0.15)
				)
				(justify left bottom)
				(hide yes)
			)
		)
		(property "License" "Apache-2.0"
			(at 363.22 139.7 0)
			(effects
				(font
					(size 1.27 1.27)
					(thickness 0.15)
				)
				(justify left bottom)
				(hide yes)
			)
		)
		(pin "1"
		)
		(instances
			(project "jetson-agx-thor-baseboard"
				(path ""
					(reference "#PWR0428")
					(unit 1)
				)
			)
		)
	)
	(symbol
		(lib_id "antmicroResistors0603:R_0R_22.4A_0603")
		(at 387.35 196.85 180)
		(unit 1)
		(exclude_from_sim no)
		(in_bom no)
		(on_board yes)
		(dnp yes)
		(property "Reference" "R247"
			(at 385.064 194.818 0)
			(effects
				(font
					(size 1.27 1.27)
					(thickness 0.15)
				)
			)
		)
		(property "Value" "R_0R_22.4A_0603"
			(at 384.81 205.74 0)
			(effects
				(font
					(size 1.27 1.27)
					(thickness 0.15)
				)
				(hide yes)
			)
		)
		(property "Footprint" "antmicro-footprints:R_0603_1608Metric"
			(at 372.11 186.69 0)
			(effects
				(font
					(size 1.27 1.27)
					(thickness 0.15)
				)
				(justify left bottom)
				(hide yes)
			)
		)
		(property "Datasheet" "https://fscdn.rohm.com/en/products/databook/datasheet/passive/resistor/chip_resistor/pmr-jpw-e.pdf"
			(at 372.11 184.15 0)
			(effects
				(font
					(size 1.27 1.27)
					(thickness 0.15)
				)
				(justify left bottom)
				(hide yes)
			)
		)
		(property "Description" "SMD Chip Resistor"
			(at 387.35 196.85 0)
			(effects
				(font
					(size 1.27 1.27)
				)
				(hide yes)
			)
		)
		(property "MPN" "PMR03EZPJ000"
			(at 372.11 181.61 0)
			(effects
				(font
					(size 1.27 1.27)
					(thickness 0.15)
				)
				(justify left bottom)
				(hide yes)
			)
		)
		(property "Manufacturer" "ROHM Semiconductor"
			(at 372.11 179.07 0)
			(effects
				(font
					(size 1.27 1.27)
					(thickness 0.15)
				)
				(justify left bottom)
				(hide yes)
			)
		)
		(property "Val" "0R"
			(at 382.778 198.882 0)
			(effects
				(font
					(size 1.27 1.27)
					(thickness 0.15)
				)
			)
		)
		(property "Max. Curr." "22.4A"
			(at 387.096 198.882 0)
			(effects
				(font
					(size 1.27 1.27)
					(thickness 0.15)
				)
			)
		)
		(property "Author" "Antmicro"
			(at 372.11 173.99 0)
			(effects
				(font
					(size 1.27 1.27)
					(thickness 0.15)
				)
				(justify left bottom)
				(hide yes)
			)
		)
		(property "License" "Apache-2.0"
			(at 372.11 171.45 0)
			(effects
				(font
					(size 1.27 1.27)
					(thickness 0.15)
				)
				(justify left bottom)
				(hide yes)
			)
		)
		(property "Tolerance" "template_tolerance"
			(at 367.03 186.69 0)
			(effects
				(font
					(size 1.27 1.27)
				)
				(justify left bottom)
				(hide yes)
			)
		)
		(pin "1"
		)
		(pin "2"
		)
		(instances
			(project "jetson-agx-thor-baseboard"
				(path ""
					(reference "R247")
					(unit 1)
				)
			)
		)
	)
	(symbol
		(lib_id "antmicropower:GND")
		(at 57.15 254 0)
		(mirror y)
		(unit 1)
		(exclude_from_sim no)
		(in_bom yes)
		(on_board yes)
		(dnp no)
		(fields_autoplaced yes)
		(property "Reference" "#PWR0450"
			(at 48.26 256.54 0)
			(effects
				(font
					(size 1.27 1.27)
					(thickness 0.15)
				)
				(justify left bottom)
				(hide yes)
			)
		)
		(property "Value" "GND"
			(at 57.15 259.08 0)
			(effects
				(font
					(size 1.27 1.27)
					(thickness 0.15)
				)
			)
		)
		(property "Footprint" ""
			(at 48.26 261.62 0)
			(effects
				(font
					(size 1.27 1.27)
					(thickness 0.15)
				)
				(justify left bottom)
				(hide yes)
			)
		)
		(property "Datasheet" ""
			(at 48.26 266.7 0)
			(effects
				(font
					(size 1.27 1.27)
					(thickness 0.15)
				)
				(justify left bottom)
				(hide yes)
			)
		)
		(property "Description" ""
			(at 57.15 254 0)
			(effects
				(font
					(size 1.27 1.27)
				)
				(hide yes)
			)
		)
		(property "Author" "Antmicro"
			(at 48.26 261.62 0)
			(effects
				(font
					(size 1.27 1.27)
					(thickness 0.15)
				)
				(justify left bottom)
				(hide yes)
			)
		)
		(property "License" "Apache-2.0"
			(at 48.26 264.16 0)
			(effects
				(font
					(size 1.27 1.27)
					(thickness 0.15)
				)
				(justify left bottom)
				(hide yes)
			)
		)
		(pin "1"
		)
		(instances
			(project "jetson-agx-thor-baseboard"
				(path ""
					(reference "#PWR0450")
					(unit 1)
				)
			)
		)
	)
	(symbol
		(lib_id "antmicroResistors0603:R_0R_22.4A_0603")
		(at 382.27 215.9 0)
		(unit 1)
		(exclude_from_sim no)
		(in_bom no)
		(on_board yes)
		(dnp yes)
		(property "Reference" "R33"
			(at 384.81 213.995 0)
			(effects
				(font
					(size 1.27 1.27)
					(thickness 0.15)
				)
			)
		)
		(property "Value" "R_0R_22.4A_0603"
			(at 384.81 207.01 0)
			(effects
				(font
					(size 1.27 1.27)
					(thickness 0.15)
				)
				(hide yes)
			)
		)
		(property "Footprint" "antmicro-footprints:R_0603_1608Metric"
			(at 397.51 226.06 0)
			(effects
				(font
					(size 1.27 1.27)
					(thickness 0.15)
				)
				(justify left bottom)
				(hide yes)
			)
		)
		(property "Datasheet" "https://fscdn.rohm.com/en/products/databook/datasheet/passive/resistor/chip_resistor/pmr-jpw-e.pdf"
			(at 397.51 228.6 0)
			(effects
				(font
					(size 1.27 1.27)
					(thickness 0.15)
				)
				(justify left bottom)
				(hide yes)
			)
		)
		(property "Description" "SMD Chip Resistor"
			(at 382.27 215.9 0)
			(effects
				(font
					(size 1.27 1.27)
				)
				(hide yes)
			)
		)
		(property "MPN" "PMR03EZPJ000"
			(at 397.51 231.14 0)
			(effects
				(font
					(size 1.27 1.27)
					(thickness 0.15)
				)
				(justify left bottom)
				(hide yes)
			)
		)
		(property "Manufacturer" "ROHM Semiconductor"
			(at 397.51 233.68 0)
			(effects
				(font
					(size 1.27 1.27)
					(thickness 0.15)
				)
				(justify left bottom)
				(hide yes)
			)
		)
		(property "Val" "0R"
			(at 387.35 218.44 0)
			(effects
				(font
					(size 1.27 1.27)
					(thickness 0.15)
				)
			)
		)
		(property "Max. Curr." "22.4A"
			(at 382.27 218.44 0)
			(effects
				(font
					(size 1.27 1.27)
					(thickness 0.15)
				)
			)
		)
		(property "Author" "Antmicro"
			(at 397.51 238.76 0)
			(effects
				(font
					(size 1.27 1.27)
					(thickness 0.15)
				)
				(justify left bottom)
				(hide yes)
			)
		)
		(property "License" "Apache-2.0"
			(at 397.51 241.3 0)
			(effects
				(font
					(size 1.27 1.27)
					(thickness 0.15)
				)
				(justify left bottom)
				(hide yes)
			)
		)
		(property "Tolerance" "template_tolerance"
			(at 402.59 226.06 0)
			(effects
				(font
					(size 1.27 1.27)
				)
				(justify left bottom)
				(hide yes)
			)
		)
		(pin "1"
		)
		(pin "2"
		)
		(instances
			(project "jetson-agx-thor-baseboard"
				(path ""
					(reference "R33")
					(unit 1)
				)
			)
		)
	)
	(symbol
		(lib_id "antmicropower:GND")
		(at 339.09 242.57 0)
		(unit 1)
		(exclude_from_sim no)
		(in_bom yes)
		(on_board yes)
		(dnp no)
		(property "Reference" "#PWR0448"
			(at 347.98 245.11 0)
			(effects
				(font
					(size 1.27 1.27)
					(thickness 0.15)
				)
				(justify left bottom)
				(hide yes)
			)
		)
		(property "Value" "GND"
			(at 339.09 246.38 0)
			(effects
				(font
					(size 1.27 1.27)
					(thickness 0.15)
				)
			)
		)
		(property "Footprint" ""
			(at 347.98 250.19 0)
			(effects
				(font
					(size 1.27 1.27)
					(thickness 0.15)
				)
				(justify left bottom)
				(hide yes)
			)
		)
		(property "Datasheet" ""
			(at 347.98 255.27 0)
			(effects
				(font
					(size 1.27 1.27)
					(thickness 0.15)
				)
				(justify left bottom)
				(hide yes)
			)
		)
		(property "Description" ""
			(at 339.09 242.57 0)
			(effects
				(font
					(size 1.27 1.27)
				)
				(hide yes)
			)
		)
		(property "Author" "Antmicro"
			(at 347.98 250.19 0)
			(effects
				(font
					(size 1.27 1.27)
					(thickness 0.15)
				)
				(justify left bottom)
				(hide yes)
			)
		)
		(property "License" "Apache-2.0"
			(at 347.98 252.73 0)
			(effects
				(font
					(size 1.27 1.27)
					(thickness 0.15)
				)
				(justify left bottom)
				(hide yes)
			)
		)
		(pin "1"
		)
		(instances
			(project "jetson-agx-thor-baseboard"
				(path ""
					(reference "#PWR0448")
					(unit 1)
				)
			)
		)
	)
	(symbol
		(lib_id "antmicropower:GND")
		(at 85.09 129.54 0)
		(mirror y)
		(unit 1)
		(exclude_from_sim no)
		(in_bom yes)
		(on_board yes)
		(dnp no)
		(fields_autoplaced yes)
		(property "Reference" "#PWR0445"
			(at 76.2 132.08 0)
			(effects
				(font
					(size 1.27 1.27)
					(thickness 0.15)
				)
				(justify left bottom)
				(hide yes)
			)
		)
		(property "Value" "GND"
			(at 85.09 134.62 0)
			(effects
				(font
					(size 1.27 1.27)
					(thickness 0.15)
				)
			)
		)
		(property "Footprint" ""
			(at 76.2 137.16 0)
			(effects
				(font
					(size 1.27 1.27)
					(thickness 0.15)
				)
				(justify left bottom)
				(hide yes)
			)
		)
		(property "Datasheet" ""
			(at 76.2 142.24 0)
			(effects
				(font
					(size 1.27 1.27)
					(thickness 0.15)
				)
				(justify left bottom)
				(hide yes)
			)
		)
		(property "Description" ""
			(at 85.09 129.54 0)
			(effects
				(font
					(size 1.27 1.27)
				)
				(hide yes)
			)
		)
		(property "Author" "Antmicro"
			(at 76.2 137.16 0)
			(effects
				(font
					(size 1.27 1.27)
					(thickness 0.15)
				)
				(justify left bottom)
				(hide yes)
			)
		)
		(property "License" "Apache-2.0"
			(at 76.2 139.7 0)
			(effects
				(font
					(size 1.27 1.27)
					(thickness 0.15)
				)
				(justify left bottom)
				(hide yes)
			)
		)
		(pin "1"
		)
		(instances
			(project "jetson-agx-thor-baseboard"
				(path ""
					(reference "#PWR0445")
					(unit 1)
				)
			)
		)
	)
	(symbol
		(lib_id "antmicropower:GND")
		(at 191.77 129.54 0)
		(unit 1)
		(exclude_from_sim no)
		(in_bom yes)
		(on_board yes)
		(dnp no)
		(fields_autoplaced yes)
		(property "Reference" "#PWR0436"
			(at 200.66 132.08 0)
			(effects
				(font
					(size 1.27 1.27)
					(thickness 0.15)
				)
				(justify left bottom)
				(hide yes)
			)
		)
		(property "Value" "GND"
			(at 191.77 134.62 0)
			(effects
				(font
					(size 1.27 1.27)
					(thickness 0.15)
				)
			)
		)
		(property "Footprint" ""
			(at 200.66 137.16 0)
			(effects
				(font
					(size 1.27 1.27)
					(thickness 0.15)
				)
				(justify left bottom)
				(hide yes)
			)
		)
		(property "Datasheet" ""
			(at 200.66 142.24 0)
			(effects
				(font
					(size 1.27 1.27)
					(thickness 0.15)
				)
				(justify left bottom)
				(hide yes)
			)
		)
		(property "Description" ""
			(at 191.77 129.54 0)
			(effects
				(font
					(size 1.27 1.27)
				)
				(hide yes)
			)
		)
		(property "Author" "Antmicro"
			(at 200.66 137.16 0)
			(effects
				(font
					(size 1.27 1.27)
					(thickness 0.15)
				)
				(justify left bottom)
				(hide yes)
			)
		)
		(property "License" "Apache-2.0"
			(at 200.66 139.7 0)
			(effects
				(font
					(size 1.27 1.27)
					(thickness 0.15)
				)
				(justify left bottom)
				(hide yes)
			)
		)
		(pin "1"
		)
		(instances
			(project "jetson-agx-thor-baseboard"
				(path ""
					(reference "#PWR0436")
					(unit 1)
				)
			)
		)
	)
	(symbol
		(lib_id "antmicroCapacitorsmisc:C_22u_25V_0805")
		(at 203.2 132.08 270)
		(mirror x)
		(unit 1)
		(exclude_from_sim no)
		(in_bom yes)
		(on_board yes)
		(dnp no)
		(fields_autoplaced yes)
		(property "Reference" "C228"
			(at 205.74 126.9936 90)
			(effects
				(font
					(size 1.27 1.27)
					(thickness 0.15)
				)
				(justify left)
			)
		)
		(property "Value" "C_22u_25V_0805"
			(at 180.34 116.84 0)
			(effects
				(font
					(size 1.27 1.27)
					(thickness 0.15)
				)
				(justify left bottom)
				(hide yes)
			)
		)
		(property "Footprint" "antmicro-footprints:C_0805_2012Metric"
			(at 177.8 116.84 0)
			(effects
				(font
					(size 1.27 1.27)
					(thickness 0.15)
				)
				(justify left bottom)
				(hide yes)
			)
		)
		(property "Datasheet" "https://product.samsungsem.com/mlcc/CL21A226MAYNNN.do"
			(at 175.26 116.84 0)
			(effects
				(font
					(size 1.27 1.27)
					(thickness 0.15)
				)
				(justify left bottom)
				(hide yes)
			)
		)
		(property "Description" "SMT Multilayer Ceramic Capacitor, 22uF, +/-20%, 25V, X5R, 0805 [2012 Metric]"
			(at 203.2 132.08 0)
			(effects
				(font
					(size 1.27 1.27)
				)
				(hide yes)
			)
		)
		(property "MPN" "CL21A226MAYNNNE"
			(at 172.72 116.84 0)
			(effects
				(font
					(size 1.27 1.27)
					(thickness 0.15)
				)
				(justify left bottom)
				(hide yes)
			)
		)
		(property "Val" "22u"
			(at 205.74 129.5336 90)
			(effects
				(font
					(size 1.27 1.27)
					(thickness 0.15)
				)
				(justify left)
			)
		)
		(property "Voltage" "25V"
			(at 205.74 132.0736 90)
			(effects
				(font
					(size 1.27 1.27)
					(thickness 0.15)
				)
				(justify left)
			)
		)
		(property "Dielectric" "X5R"
			(at 190.5 116.84 0)
			(effects
				(font
					(size 1.27 1.27)
					(thickness 0.15)
				)
				(justify left bottom)
				(hide yes)
			)
		)
		(property "Manufacturer" "Samsung Electro-Mechanics"
			(at 187.96 116.84 0)
			(effects
				(font
					(size 1.27 1.27)
					(thickness 0.15)
				)
				(justify left bottom)
				(hide yes)
			)
		)
		(property "License" "Apache-2.0"
			(at 185.42 116.84 0)
			(effects
				(font
					(size 1.27 1.27)
					(thickness 0.15)
				)
				(justify left bottom)
				(hide yes)
			)
		)
		(property "Author" "Antmicro"
			(at 182.88 116.84 0)
			(effects
				(font
					(size 1.27 1.27)
					(thickness 0.15)
				)
				(justify left bottom)
				(hide yes)
			)
		)
		(property "Public" "False"
			(at 170.18 111.76 0)
			(effects
				(font
					(size 1.27 1.27)
				)
				(justify left bottom)
				(hide yes)
			)
		)
		(pin "2"
		)
		(pin "1"
		)
		(instances
			(project "jetson-agx-thor-baseboard"
				(path ""
					(reference "C228")
					(unit 1)
				)
			)
		)
	)
	(symbol
		(lib_id "antmicroTestPoints:TP_0.75mm_SMD")
		(at 83.82 153.67 0)
		(unit 1)
		(exclude_from_sim no)
		(in_bom no)
		(on_board yes)
		(dnp no)
		(property "Reference" "TP113"
			(at 88.138 153.67 0)
			(effects
				(font
					(size 1.27 1.27)
					(thickness 0.15)
				)
				(justify left)
			)
		)
		(property "Value" "TP_0.75mm_SMD"
			(at 93.98 157.48 0)
			(effects
				(font
					(size 1.27 1.27)
					(thickness 0.15)
				)
				(justify left bottom)
				(hide yes)
			)
		)
		(property "Footprint" "antmicro-footprints:TP_SMD_0.75mm"
			(at 93.98 160.02 0)
			(effects
				(font
					(size 1.27 1.27)
					(thickness 0.15)
				)
				(justify left bottom)
				(hide yes)
			)
		)
		(property "Datasheet" ""
			(at 101.6 166.37 0)
			(effects
				(font
					(size 1.27 1.27)
					(thickness 0.15)
				)
				(justify left bottom)
				(hide yes)
			)
		)
		(property "Description" "SMT test point"
			(at 94.615 167.64 0)
			(effects
				(font
					(size 1.27 1.27)
				)
				(justify left bottom)
				(hide yes)
			)
		)
		(property "MPN" ""
			(at 94.615 165.1 0)
			(effects
				(font
					(size 1.27 1.27)
					(thickness 0.15)
				)
				(justify left bottom)
				(hide yes)
			)
		)
		(property "Manufacturer" ""
			(at 94.615 160.02 0)
			(effects
				(font
					(size 1.27 1.27)
					(thickness 0.15)
				)
				(justify left bottom)
				(hide yes)
			)
		)
		(property "Author" "Antmicro"
			(at 93.98 162.56 0)
			(effects
				(font
					(size 1.27 1.27)
					(thickness 0.15)
				)
				(justify left bottom)
				(hide yes)
			)
		)
		(property "License" "Apache-2.0"
			(at 93.98 165.1 0)
			(effects
				(font
					(size 1.27 1.27)
					(thickness 0.15)
				)
				(justify left bottom)
				(hide yes)
			)
		)
		(pin "1"
		)
		(instances
			(project "jetson-agx-thor-baseboard"
				(path ""
					(reference "TP113")
					(unit 1)
				)
			)
		)
	)
	(symbol
		(lib_id "antmicroCapacitors0402:C_220n_0402")
		(at 261.62 240.03 0)
		(mirror y)
		(unit 1)
		(exclude_from_sim no)
		(in_bom yes)
		(on_board yes)
		(dnp no)
		(fields_autoplaced yes)
		(property "Reference" "C219"
			(at 262.636 238.76 0)
			(effects
				(font
					(size 1.27 1.27)
					(thickness 0.15)
				)
			)
		)
		(property "Value" "C_220n_0402"
			(at 246.38 262.89 0)
			(effects
				(font
					(size 1.27 1.27)
					(thickness 0.15)
				)
				(justify left bottom)
				(hide yes)
			)
		)
		(property "Footprint" "antmicro-footprints:C_0402_1005Metric"
			(at 246.38 265.43 0)
			(effects
				(font
					(size 1.27 1.27)
					(thickness 0.15)
				)
				(justify left bottom)
				(hide yes)
			)
		)
		(property "Datasheet" "https://www.yageo.com/en/Chart/Download/pdf/CC0402KRX5R6BB224"
			(at 246.38 267.97 0)
			(effects
				(font
					(size 1.27 1.27)
					(thickness 0.15)
				)
				(justify left bottom)
				(hide yes)
			)
		)
		(property "Description" "SMD Multilayer Ceramic Capacitor, 0.22 µF, 10 V, 0402 [1005 Metric], ± 10%, X5R, CC Series"
			(at 261.62 240.03 0)
			(effects
				(font
					(size 1.27 1.27)
				)
				(hide yes)
			)
		)
		(property "MPN" "CC0402KRX5R6BB224"
			(at 246.38 270.51 0)
			(effects
				(font
					(size 1.27 1.27)
					(thickness 0.15)
				)
				(justify left bottom)
				(hide yes)
			)
		)
		(property "Val" "220n"
			(at 255.27 238.76 0)
			(effects
				(font
					(size 1.27 1.27)
					(thickness 0.15)
				)
			)
		)
		(property "Voltage" "25V"
			(at 246.38 250.19 0)
			(effects
				(font
					(size 1.27 1.27)
					(thickness 0.15)
				)
				(justify left bottom)
				(hide yes)
			)
		)
		(property "Dielectric" "X7R"
			(at 246.38 252.73 0)
			(effects
				(font
					(size 1.27 1.27)
					(thickness 0.15)
				)
				(justify left bottom)
				(hide yes)
			)
		)
		(property "Manufacturer" "YAGEO"
			(at 246.38 255.27 0)
			(effects
				(font
					(size 1.27 1.27)
					(thickness 0.15)
				)
				(justify left bottom)
				(hide yes)
			)
		)
		(property "License" "Apache-2.0"
			(at 246.38 257.81 0)
			(effects
				(font
					(size 1.27 1.27)
					(thickness 0.15)
				)
				(justify left bottom)
				(hide yes)
			)
		)
		(property "Author" "Antmicro"
			(at 246.38 260.35 0)
			(effects
				(font
					(size 1.27 1.27)
					(thickness 0.15)
				)
				(justify left bottom)
				(hide yes)
			)
		)
		(property "Public" "False"
			(at 241.3 273.05 0)
			(effects
				(font
					(size 1.27 1.27)
				)
				(justify left bottom)
				(hide yes)
			)
		)
		(pin "2"
		)
		(pin "1"
		)
		(instances
			(project "jetson-agx-thor-baseboard"
				(path ""
					(reference "C219")
					(unit 1)
				)
			)
		)
	)
	(symbol
		(lib_id "antmicropower:GND")
		(at 110.49 129.54 0)
		(unit 1)
		(exclude_from_sim no)
		(in_bom yes)
		(on_board yes)
		(dnp no)
		(fields_autoplaced yes)
		(property "Reference" "#PWR0443"
			(at 119.38 132.08 0)
			(effects
				(font
					(size 1.27 1.27)
					(thickness 0.15)
				)
				(justify left bottom)
				(hide yes)
			)
		)
		(property "Value" "GND"
			(at 110.49 134.62 0)
			(effects
				(font
					(size 1.27 1.27)
					(thickness 0.15)
				)
			)
		)
		(property "Footprint" ""
			(at 119.38 137.16 0)
			(effects
				(font
					(size 1.27 1.27)
					(thickness 0.15)
				)
				(justify left bottom)
				(hide yes)
			)
		)
		(property "Datasheet" ""
			(at 119.38 142.24 0)
			(effects
				(font
					(size 1.27 1.27)
					(thickness 0.15)
				)
				(justify left bottom)
				(hide yes)
			)
		)
		(property "Description" ""
			(at 110.49 129.54 0)
			(effects
				(font
					(size 1.27 1.27)
				)
				(hide yes)
			)
		)
		(property "Author" "Antmicro"
			(at 119.38 137.16 0)
			(effects
				(font
					(size 1.27 1.27)
					(thickness 0.15)
				)
				(justify left bottom)
				(hide yes)
			)
		)
		(property "License" "Apache-2.0"
			(at 119.38 139.7 0)
			(effects
				(font
					(size 1.27 1.27)
					(thickness 0.15)
				)
				(justify left bottom)
				(hide yes)
			)
		)
		(pin "1"
		)
		(instances
			(project "jetson-agx-thor-baseboard"
				(path ""
					(reference "#PWR0443")
					(unit 1)
				)
			)
		)
	)
	(symbol
		(lib_id "antmicropower:GND")
		(at 334.01 189.23 0)
		(unit 1)
		(exclude_from_sim no)
		(in_bom yes)
		(on_board yes)
		(dnp no)
		(fields_autoplaced yes)
		(property "Reference" "#PWR06"
			(at 342.9 191.77 0)
			(effects
				(font
					(size 1.27 1.27)
					(thickness 0.15)
				)
				(justify left bottom)
				(hide yes)
			)
		)
		(property "Value" "GND"
			(at 334.01 194.31 0)
			(effects
				(font
					(size 1.27 1.27)
					(thickness 0.15)
				)
			)
		)
		(property "Footprint" ""
			(at 342.9 196.85 0)
			(effects
				(font
					(size 1.27 1.27)
					(thickness 0.15)
				)
				(justify left bottom)
				(hide yes)
			)
		)
		(property "Datasheet" ""
			(at 342.9 201.93 0)
			(effects
				(font
					(size 1.27 1.27)
					(thickness 0.15)
				)
				(justify left bottom)
				(hide yes)
			)
		)
		(property "Description" ""
			(at 342.9 204.47 0)
			(effects
				(font
					(size 1.27 1.27)
				)
				(justify left bottom)
				(hide yes)
			)
		)
		(property "Author" "Antmicro"
			(at 342.9 196.85 0)
			(effects
				(font
					(size 1.27 1.27)
					(thickness 0.15)
				)
				(justify left bottom)
				(hide yes)
			)
		)
		(property "License" "Apache-2.0"
			(at 342.9 199.39 0)
			(effects
				(font
					(size 1.27 1.27)
					(thickness 0.15)
				)
				(justify left bottom)
				(hide yes)
			)
		)
		(pin "1"
		)
		(instances
			(project "jetson-agx-thor-baseboard"
				(path ""
					(reference "#PWR06")
					(unit 1)
				)
			)
		)
	)
	(symbol
		(lib_id "antmicropower:GND")
		(at 144.78 254 0)
		(unit 1)
		(exclude_from_sim no)
		(in_bom yes)
		(on_board yes)
		(dnp no)
		(fields_autoplaced yes)
		(property "Reference" "#PWR0444"
			(at 153.67 256.54 0)
			(effects
				(font
					(size 1.27 1.27)
					(thickness 0.15)
				)
				(justify left bottom)
				(hide yes)
			)
		)
		(property "Value" "GND"
			(at 144.78 259.08 0)
			(effects
				(font
					(size 1.27 1.27)
					(thickness 0.15)
				)
			)
		)
		(property "Footprint" ""
			(at 153.67 261.62 0)
			(effects
				(font
					(size 1.27 1.27)
					(thickness 0.15)
				)
				(justify left bottom)
				(hide yes)
			)
		)
		(property "Datasheet" ""
			(at 153.67 266.7 0)
			(effects
				(font
					(size 1.27 1.27)
					(thickness 0.15)
				)
				(justify left bottom)
				(hide yes)
			)
		)
		(property "Description" ""
			(at 144.78 254 0)
			(effects
				(font
					(size 1.27 1.27)
				)
				(hide yes)
			)
		)
		(property "Author" "Antmicro"
			(at 153.67 261.62 0)
			(effects
				(font
					(size 1.27 1.27)
					(thickness 0.15)
				)
				(justify left bottom)
				(hide yes)
			)
		)
		(property "License" "Apache-2.0"
			(at 153.67 264.16 0)
			(effects
				(font
					(size 1.27 1.27)
					(thickness 0.15)
				)
				(justify left bottom)
				(hide yes)
			)
		)
		(pin "1"
		)
		(instances
			(project "jetson-agx-thor-baseboard"
				(path ""
					(reference "#PWR0444")
					(unit 1)
				)
			)
		)
	)
	(symbol
		(lib_id "antmicropower:GND")
		(at 237.49 254 0)
		(unit 1)
		(exclude_from_sim no)
		(in_bom yes)
		(on_board yes)
		(dnp no)
		(fields_autoplaced yes)
		(property "Reference" "#PWR0427"
			(at 246.38 256.54 0)
			(effects
				(font
					(size 1.27 1.27)
					(thickness 0.15)
				)
				(justify left bottom)
				(hide yes)
			)
		)
		(property "Value" "GND"
			(at 237.49 259.08 0)
			(effects
				(font
					(size 1.27 1.27)
					(thickness 0.15)
				)
			)
		)
		(property "Footprint" ""
			(at 246.38 261.62 0)
			(effects
				(font
					(size 1.27 1.27)
					(thickness 0.15)
				)
				(justify left bottom)
				(hide yes)
			)
		)
		(property "Datasheet" ""
			(at 246.38 266.7 0)
			(effects
				(font
					(size 1.27 1.27)
					(thickness 0.15)
				)
				(justify left bottom)
				(hide yes)
			)
		)
		(property "Description" ""
			(at 237.49 254 0)
			(effects
				(font
					(size 1.27 1.27)
				)
				(hide yes)
			)
		)
		(property "Author" "Antmicro"
			(at 246.38 261.62 0)
			(effects
				(font
					(size 1.27 1.27)
					(thickness 0.15)
				)
				(justify left bottom)
				(hide yes)
			)
		)
		(property "License" "Apache-2.0"
			(at 246.38 264.16 0)
			(effects
				(font
					(size 1.27 1.27)
					(thickness 0.15)
				)
				(justify left bottom)
				(hide yes)
			)
		)
		(pin "1"
		)
		(instances
			(project "jetson-agx-thor-baseboard"
				(path ""
					(reference "#PWR0427")
					(unit 1)
				)
			)
		)
	)
	(symbol
		(lib_id "antmicropower:GND")
		(at 166.37 129.54 0)
		(mirror y)
		(unit 1)
		(exclude_from_sim no)
		(in_bom yes)
		(on_board yes)
		(dnp no)
		(fields_autoplaced yes)
		(property "Reference" "#PWR0438"
			(at 157.48 132.08 0)
			(effects
				(font
					(size 1.27 1.27)
					(thickness 0.15)
				)
				(justify left bottom)
				(hide yes)
			)
		)
		(property "Value" "GND"
			(at 166.37 134.62 0)
			(effects
				(font
					(size 1.27 1.27)
					(thickness 0.15)
				)
			)
		)
		(property "Footprint" ""
			(at 157.48 137.16 0)
			(effects
				(font
					(size 1.27 1.27)
					(thickness 0.15)
				)
				(justify left bottom)
				(hide yes)
			)
		)
		(property "Datasheet" ""
			(at 157.48 142.24 0)
			(effects
				(font
					(size 1.27 1.27)
					(thickness 0.15)
				)
				(justify left bottom)
				(hide yes)
			)
		)
		(property "Description" ""
			(at 166.37 129.54 0)
			(effects
				(font
					(size 1.27 1.27)
				)
				(hide yes)
			)
		)
		(property "Author" "Antmicro"
			(at 157.48 137.16 0)
			(effects
				(font
					(size 1.27 1.27)
					(thickness 0.15)
				)
				(justify left bottom)
				(hide yes)
			)
		)
		(property "License" "Apache-2.0"
			(at 157.48 139.7 0)
			(effects
				(font
					(size 1.27 1.27)
					(thickness 0.15)
				)
				(justify left bottom)
				(hide yes)
			)
		)
		(pin "1"
		)
		(instances
			(project "jetson-agx-thor-baseboard"
				(path ""
					(reference "#PWR0438")
					(unit 1)
				)
			)
		)
	)
	(symbol
		(lib_id "antmicropower:+1V8")
		(at 379.73 204.47 0)
		(unit 1)
		(exclude_from_sim no)
		(in_bom yes)
		(on_board yes)
		(dnp no)
		(property "Reference" "#PWR012"
			(at 379.73 208.28 0)
			(effects
				(font
					(size 1.27 1.27)
				)
				(justify left bottom)
				(hide yes)
			)
		)
		(property "Value" "+1V8"
			(at 376.555 200.66 0)
			(effects
				(font
					(size 1.27 1.27)
					(thickness 0.15)
				)
				(justify left)
			)
		)
		(property "Footprint" ""
			(at 394.97 212.09 0)
			(effects
				(font
					(size 1.27 1.27)
					(thickness 0.15)
				)
				(justify left bottom)
				(hide yes)
			)
		)
		(property "Datasheet" ""
			(at 394.97 214.63 0)
			(effects
				(font
					(size 1.27 1.27)
					(thickness 0.15)
				)
				(justify left bottom)
				(hide yes)
			)
		)
		(property "Description" ""
			(at 379.73 204.47 0)
			(effects
				(font
					(size 1.27 1.27)
				)
				(hide yes)
			)
		)
		(property "Author" "Antmicro"
			(at 394.97 209.55 0)
			(effects
				(font
					(size 1.27 1.27)
					(thickness 0.15)
				)
				(justify left bottom)
				(hide yes)
			)
		)
		(property "License" "Apache-2.0"
			(at 394.97 212.09 0)
			(effects
				(font
					(size 1.27 1.27)
					(thickness 0.15)
				)
				(justify left bottom)
				(hide yes)
			)
		)
		(pin "1"
		)
		(instances
			(project "jetson-agx-thor-baseboard"
				(path ""
					(reference "#PWR012")
					(unit 1)
				)
			)
		)
	)
	(symbol
		(lib_id "antmicroCapacitorsmisc:C_22u_25V_0805")
		(at 349.25 234.95 90)
		(unit 1)
		(exclude_from_sim no)
		(in_bom yes)
		(on_board yes)
		(dnp no)
		(property "Reference" "C50"
			(at 346.71 229.8636 90)
			(effects
				(font
					(size 1.27 1.27)
					(thickness 0.15)
				)
				(justify left)
			)
		)
		(property "Value" "C_22u_25V_0805"
			(at 372.11 219.71 0)
			(effects
				(font
					(size 1.27 1.27)
					(thickness 0.15)
				)
				(justify left bottom)
				(hide yes)
			)
		)
		(property "Footprint" "antmicro-footprints:C_0805_2012Metric"
			(at 374.65 219.71 0)
			(effects
				(font
					(size 1.27 1.27)
					(thickness 0.15)
				)
				(justify left bottom)
				(hide yes)
			)
		)
		(property "Datasheet" "https://product.samsungsem.com/mlcc/CL21A226MAYNNN.do"
			(at 377.19 219.71 0)
			(effects
				(font
					(size 1.27 1.27)
					(thickness 0.15)
				)
				(justify left bottom)
				(hide yes)
			)
		)
		(property "Description" "SMT Multilayer Ceramic Capacitor, 22uF, +/-20%, 25V, X5R, 0805 [2012 Metric]"
			(at 349.25 234.95 0)
			(effects
				(font
					(size 1.27 1.27)
				)
				(hide yes)
			)
		)
		(property "MPN" "CL21A226MAYNNNE"
			(at 379.73 219.71 0)
			(effects
				(font
					(size 1.27 1.27)
					(thickness 0.15)
				)
				(justify left bottom)
				(hide yes)
			)
		)
		(property "Val" "22u"
			(at 346.71 232.4036 90)
			(effects
				(font
					(size 1.27 1.27)
					(thickness 0.15)
				)
				(justify left)
			)
		)
		(property "Voltage" "25V"
			(at 346.71 234.9436 90)
			(effects
				(font
					(size 1.27 1.27)
					(thickness 0.15)
				)
				(justify left)
			)
		)
		(property "Dielectric" "X5R"
			(at 361.95 219.71 0)
			(effects
				(font
					(size 1.27 1.27)
					(thickness 0.15)
				)
				(justify left bottom)
				(hide yes)
			)
		)
		(property "Manufacturer" "Samsung Electro-Mechanics"
			(at 364.49 219.71 0)
			(effects
				(font
					(size 1.27 1.27)
					(thickness 0.15)
				)
				(justify left bottom)
				(hide yes)
			)
		)
		(property "License" "Apache-2.0"
			(at 367.03 219.71 0)
			(effects
				(font
					(size 1.27 1.27)
					(thickness 0.15)
				)
				(justify left bottom)
				(hide yes)
			)
		)
		(property "Author" "Antmicro"
			(at 369.57 219.71 0)
			(effects
				(font
					(size 1.27 1.27)
					(thickness 0.15)
				)
				(justify left bottom)
				(hide yes)
			)
		)
		(property "Public" "False"
			(at 382.27 214.63 0)
			(effects
				(font
					(size 1.27 1.27)
				)
				(justify left bottom)
				(hide yes)
			)
		)
		(pin "2"
		)
		(pin "1"
		)
		(instances
			(project "jetson-agx-thor-baseboard"
				(path ""
					(reference "C50")
					(unit 1)
				)
			)
		)
	)
	(symbol
		(lib_id "antmicropower:GND")
		(at 367.03 236.22 0)
		(mirror y)
		(unit 1)
		(exclude_from_sim no)
		(in_bom yes)
		(on_board yes)
		(dnp no)
		(property "Reference" "#PWR0439"
			(at 358.14 238.76 0)
			(effects
				(font
					(size 1.27 1.27)
					(thickness 0.15)
				)
				(justify left bottom)
				(hide yes)
			)
		)
		(property "Value" "GND"
			(at 367.03 240.03 0)
			(effects
				(font
					(size 1.27 1.27)
					(thickness 0.15)
				)
			)
		)
		(property "Footprint" ""
			(at 358.14 243.84 0)
			(effects
				(font
					(size 1.27 1.27)
					(thickness 0.15)
				)
				(justify left bottom)
				(hide yes)
			)
		)
		(property "Datasheet" ""
			(at 358.14 248.92 0)
			(effects
				(font
					(size 1.27 1.27)
					(thickness 0.15)
				)
				(justify left bottom)
				(hide yes)
			)
		)
		(property "Description" ""
			(at 367.03 236.22 0)
			(effects
				(font
					(size 1.27 1.27)
				)
				(hide yes)
			)
		)
		(property "Author" "Antmicro"
			(at 358.14 243.84 0)
			(effects
				(font
					(size 1.27 1.27)
					(thickness 0.15)
				)
				(justify left bottom)
				(hide yes)
			)
		)
		(property "License" "Apache-2.0"
			(at 358.14 246.38 0)
			(effects
				(font
					(size 1.27 1.27)
					(thickness 0.15)
				)
				(justify left bottom)
				(hide yes)
			)
		)
		(pin "1"
		)
		(instances
			(project "jetson-agx-thor-baseboard"
				(path ""
					(reference "#PWR0439")
					(unit 1)
				)
			)
		)
	)
	(symbol
		(lib_id "antmicroTestPoints:TP_0.75mm_SMD")
		(at 327.66 128.27 0)
		(mirror y)
		(unit 1)
		(exclude_from_sim no)
		(in_bom no)
		(on_board yes)
		(dnp no)
		(fields_autoplaced yes)
		(property "Reference" "TP72"
			(at 322.58 128.27 0)
			(effects
				(font
					(size 1.27 1.27)
					(thickness 0.15)
				)
				(justify left)
			)
		)
		(property "Value" "TP_0.75mm_SMD"
			(at 317.5 132.08 0)
			(effects
				(font
					(size 1.27 1.27)
					(thickness 0.15)
				)
				(justify left bottom)
				(hide yes)
			)
		)
		(property "Footprint" "antmicro-footprints:TP_SMD_0.75mm"
			(at 317.5 134.62 0)
			(effects
				(font
					(size 1.27 1.27)
					(thickness 0.15)
				)
				(justify left bottom)
				(hide yes)
			)
		)
		(property "Datasheet" ""
			(at 309.88 140.97 0)
			(effects
				(font
					(size 1.27 1.27)
					(thickness 0.15)
				)
				(justify left bottom)
				(hide yes)
			)
		)
		(property "Description" "SMT test point"
			(at 316.865 142.24 0)
			(effects
				(font
					(size 1.27 1.27)
				)
				(justify left bottom)
				(hide yes)
			)
		)
		(property "MPN" ""
			(at 316.865 139.7 0)
			(effects
				(font
					(size 1.27 1.27)
					(thickness 0.15)
				)
				(justify left bottom)
				(hide yes)
			)
		)
		(property "Manufacturer" ""
			(at 316.865 134.62 0)
			(effects
				(font
					(size 1.27 1.27)
					(thickness 0.15)
				)
				(justify left bottom)
				(hide yes)
			)
		)
		(property "Author" "Antmicro"
			(at 317.5 137.16 0)
			(effects
				(font
					(size 1.27 1.27)
					(thickness 0.15)
				)
				(justify left bottom)
				(hide yes)
			)
		)
		(property "License" "Apache-2.0"
			(at 317.5 139.7 0)
			(effects
				(font
					(size 1.27 1.27)
					(thickness 0.15)
				)
				(justify left bottom)
				(hide yes)
			)
		)
		(pin "1"
		)
		(instances
			(project ""
				(path ""
					(reference "TP72")
					(unit 1)
				)
			)
		)
	)
	(symbol
		(lib_id "antmicropower:GND")
		(at 203.2 132.08 0)
		(mirror y)
		(unit 1)
		(exclude_from_sim no)
		(in_bom yes)
		(on_board yes)
		(dnp no)
		(property "Reference" "#PWR0434"
			(at 194.31 134.62 0)
			(effects
				(font
					(size 1.27 1.27)
					(thickness 0.15)
				)
				(justify left bottom)
				(hide yes)
			)
		)
		(property "Value" "GND"
			(at 203.2 135.89 0)
			(effects
				(font
					(size 1.27 1.27)
					(thickness 0.15)
				)
			)
		)
		(property "Footprint" ""
			(at 194.31 139.7 0)
			(effects
				(font
					(size 1.27 1.27)
					(thickness 0.15)
				)
				(justify left bottom)
				(hide yes)
			)
		)
		(property "Datasheet" ""
			(at 194.31 144.78 0)
			(effects
				(font
					(size 1.27 1.27)
					(thickness 0.15)
				)
				(justify left bottom)
				(hide yes)
			)
		)
		(property "Description" ""
			(at 203.2 132.08 0)
			(effects
				(font
					(size 1.27 1.27)
				)
				(hide yes)
			)
		)
		(property "Author" "Antmicro"
			(at 194.31 139.7 0)
			(effects
				(font
					(size 1.27 1.27)
					(thickness 0.15)
				)
				(justify left bottom)
				(hide yes)
			)
		)
		(property "License" "Apache-2.0"
			(at 194.31 142.24 0)
			(effects
				(font
					(size 1.27 1.27)
					(thickness 0.15)
				)
				(justify left bottom)
				(hide yes)
			)
		)
		(pin "1"
		)
		(instances
			(project "jetson-agx-thor-baseboard"
				(path ""
					(reference "#PWR0434")
					(unit 1)
				)
			)
		)
	)
	(symbol
		(lib_id "antmicroCapacitorsmisc:C_22u_25V_0805")
		(at 97.79 248.92 270)
		(mirror x)
		(unit 1)
		(exclude_from_sim no)
		(in_bom yes)
		(on_board yes)
		(dnp no)
		(property "Reference" "C227"
			(at 100.33 243.8336 90)
			(effects
				(font
					(size 1.27 1.27)
					(thickness 0.15)
				)
				(justify left)
			)
		)
		(property "Value" "C_22u_25V_0805"
			(at 74.93 233.68 0)
			(effects
				(font
					(size 1.27 1.27)
					(thickness 0.15)
				)
				(justify left bottom)
				(hide yes)
			)
		)
		(property "Footprint" "antmicro-footprints:C_0805_2012Metric"
			(at 72.39 233.68 0)
			(effects
				(font
					(size 1.27 1.27)
					(thickness 0.15)
				)
				(justify left bottom)
				(hide yes)
			)
		)
		(property "Datasheet" "https://product.samsungsem.com/mlcc/CL21A226MAYNNN.do"
			(at 69.85 233.68 0)
			(effects
				(font
					(size 1.27 1.27)
					(thickness 0.15)
				)
				(justify left bottom)
				(hide yes)
			)
		)
		(property "Description" "SMT Multilayer Ceramic Capacitor, 22uF, +/-20%, 25V, X5R, 0805 [2012 Metric]"
			(at 97.79 248.92 0)
			(effects
				(font
					(size 1.27 1.27)
				)
				(hide yes)
			)
		)
		(property "MPN" "CL21A226MAYNNNE"
			(at 67.31 233.68 0)
			(effects
				(font
					(size 1.27 1.27)
					(thickness 0.15)
				)
				(justify left bottom)
				(hide yes)
			)
		)
		(property "Val" "22u"
			(at 100.33 246.3736 90)
			(effects
				(font
					(size 1.27 1.27)
					(thickness 0.15)
				)
				(justify left)
			)
		)
		(property "Voltage" "25V"
			(at 100.33 248.9136 90)
			(effects
				(font
					(size 1.27 1.27)
					(thickness 0.15)
				)
				(justify left)
			)
		)
		(property "Dielectric" "X5R"
			(at 85.09 233.68 0)
			(effects
				(font
					(size 1.27 1.27)
					(thickness 0.15)
				)
				(justify left bottom)
				(hide yes)
			)
		)
		(property "Manufacturer" "Samsung Electro-Mechanics"
			(at 82.55 233.68 0)
			(effects
				(font
					(size 1.27 1.27)
					(thickness 0.15)
				)
				(justify left bottom)
				(hide yes)
			)
		)
		(property "License" "Apache-2.0"
			(at 80.01 233.68 0)
			(effects
				(font
					(size 1.27 1.27)
					(thickness 0.15)
				)
				(justify left bottom)
				(hide yes)
			)
		)
		(property "Author" "Antmicro"
			(at 77.47 233.68 0)
			(effects
				(font
					(size 1.27 1.27)
					(thickness 0.15)
				)
				(justify left bottom)
				(hide yes)
			)
		)
		(property "Public" "False"
			(at 64.77 228.6 0)
			(effects
				(font
					(size 1.27 1.27)
				)
				(justify left bottom)
				(hide yes)
			)
		)
		(pin "2"
		)
		(pin "1"
		)
		(instances
			(project "jetson-agx-thor-baseboard"
				(path ""
					(reference "C227")
					(unit 1)
				)
			)
		)
	)
	(symbol
		(lib_id "antmicropower:GND")
		(at 119.38 254 0)
		(mirror y)
		(unit 1)
		(exclude_from_sim no)
		(in_bom yes)
		(on_board yes)
		(dnp no)
		(fields_autoplaced yes)
		(property "Reference" "#PWR0446"
			(at 110.49 256.54 0)
			(effects
				(font
					(size 1.27 1.27)
					(thickness 0.15)
				)
				(justify left bottom)
				(hide yes)
			)
		)
		(property "Value" "GND"
			(at 119.38 259.08 0)
			(effects
				(font
					(size 1.27 1.27)
					(thickness 0.15)
				)
			)
		)
		(property "Footprint" ""
			(at 110.49 261.62 0)
			(effects
				(font
					(size 1.27 1.27)
					(thickness 0.15)
				)
				(justify left bottom)
				(hide yes)
			)
		)
		(property "Datasheet" ""
			(at 110.49 266.7 0)
			(effects
				(font
					(size 1.27 1.27)
					(thickness 0.15)
				)
				(justify left bottom)
				(hide yes)
			)
		)
		(property "Description" ""
			(at 119.38 254 0)
			(effects
				(font
					(size 1.27 1.27)
				)
				(hide yes)
			)
		)
		(property "Author" "Antmicro"
			(at 110.49 261.62 0)
			(effects
				(font
					(size 1.27 1.27)
					(thickness 0.15)
				)
				(justify left bottom)
				(hide yes)
			)
		)
		(property "License" "Apache-2.0"
			(at 110.49 264.16 0)
			(effects
				(font
					(size 1.27 1.27)
					(thickness 0.15)
				)
				(justify left bottom)
				(hide yes)
			)
		)
		(pin "1"
		)
		(instances
			(project "jetson-agx-thor-baseboard"
				(path ""
					(reference "#PWR0446")
					(unit 1)
				)
			)
		)
	)
	(symbol
		(lib_id "antmicroCapacitors0402:C_220n_0402")
		(at 189.23 242.57 0)
		(unit 1)
		(exclude_from_sim no)
		(in_bom yes)
		(on_board yes)
		(dnp no)
		(fields_autoplaced yes)
		(property "Reference" "C213"
			(at 192.024 237.236 0)
			(effects
				(font
					(size 1.27 1.27)
					(thickness 0.15)
				)
			)
		)
		(property "Value" "C_220n_0402"
			(at 204.47 265.43 0)
			(effects
				(font
					(size 1.27 1.27)
					(thickness 0.15)
				)
				(justify left bottom)
				(hide yes)
			)
		)
		(property "Footprint" "antmicro-footprints:C_0402_1005Metric"
			(at 204.47 267.97 0)
			(effects
				(font
					(size 1.27 1.27)
					(thickness 0.15)
				)
				(justify left bottom)
				(hide yes)
			)
		)
		(property "Datasheet" "https://www.yageo.com/en/Chart/Download/pdf/CC0402KRX5R6BB224"
			(at 204.47 270.51 0)
			(effects
				(font
					(size 1.27 1.27)
					(thickness 0.15)
				)
				(justify left bottom)
				(hide yes)
			)
		)
		(property "Description" "SMD Multilayer Ceramic Capacitor, 0.22 µF, 10 V, 0402 [1005 Metric], ± 10%, X5R, CC Series"
			(at 189.23 242.57 0)
			(effects
				(font
					(size 1.27 1.27)
				)
				(hide yes)
			)
		)
		(property "MPN" "CC0402KRX5R6BB224"
			(at 204.47 273.05 0)
			(effects
				(font
					(size 1.27 1.27)
					(thickness 0.15)
				)
				(justify left bottom)
				(hide yes)
			)
		)
		(property "Val" "220n"
			(at 192.024 239.776 0)
			(effects
				(font
					(size 1.27 1.27)
					(thickness 0.15)
				)
			)
		)
		(property "Voltage" "25V"
			(at 204.47 252.73 0)
			(effects
				(font
					(size 1.27 1.27)
					(thickness 0.15)
				)
				(justify left bottom)
				(hide yes)
			)
		)
		(property "Dielectric" "X7R"
			(at 204.47 255.27 0)
			(effects
				(font
					(size 1.27 1.27)
					(thickness 0.15)
				)
				(justify left bottom)
				(hide yes)
			)
		)
		(property "Manufacturer" "YAGEO"
			(at 204.47 257.81 0)
			(effects
				(font
					(size 1.27 1.27)
					(thickness 0.15)
				)
				(justify left bottom)
				(hide yes)
			)
		)
		(property "License" "Apache-2.0"
			(at 204.47 260.35 0)
			(effects
				(font
					(size 1.27 1.27)
					(thickness 0.15)
				)
				(justify left bottom)
				(hide yes)
			)
		)
		(property "Author" "Antmicro"
			(at 204.47 262.89 0)
			(effects
				(font
					(size 1.27 1.27)
					(thickness 0.15)
				)
				(justify left bottom)
				(hide yes)
			)
		)
		(property "Public" "False"
			(at 209.55 275.59 0)
			(effects
				(font
					(size 1.27 1.27)
				)
				(justify left bottom)
				(hide yes)
			)
		)
		(pin "2"
		)
		(pin "1"
		)
		(instances
			(project "jetson-agx-thor-baseboard"
				(path ""
					(reference "C213")
					(unit 1)
				)
			)
		)
	)
	(symbol
		(lib_id "antmicropower:GND")
		(at 353.06 189.23 0)
		(mirror y)
		(unit 1)
		(exclude_from_sim no)
		(in_bom yes)
		(on_board yes)
		(dnp no)
		(property "Reference" "#PWR08"
			(at 344.17 191.77 0)
			(effects
				(font
					(size 1.27 1.27)
					(thickness 0.15)
				)
				(justify left bottom)
				(hide yes)
			)
		)
		(property "Value" "GND"
			(at 353.06 193.294 0)
			(effects
				(font
					(size 1.27 1.27)
					(thickness 0.15)
				)
			)
		)
		(property "Footprint" ""
			(at 344.17 196.85 0)
			(effects
				(font
					(size 1.27 1.27)
					(thickness 0.15)
				)
				(justify left bottom)
				(hide yes)
			)
		)
		(property "Datasheet" ""
			(at 344.17 201.93 0)
			(effects
				(font
					(size 1.27 1.27)
					(thickness 0.15)
				)
				(justify left bottom)
				(hide yes)
			)
		)
		(property "Description" ""
			(at 344.17 204.47 0)
			(effects
				(font
					(size 1.27 1.27)
				)
				(justify left bottom)
				(hide yes)
			)
		)
		(property "Author" "Antmicro"
			(at 344.17 196.85 0)
			(effects
				(font
					(size 1.27 1.27)
					(thickness 0.15)
				)
				(justify left bottom)
				(hide yes)
			)
		)
		(property "License" "Apache-2.0"
			(at 344.17 199.39 0)
			(effects
				(font
					(size 1.27 1.27)
					(thickness 0.15)
				)
				(justify left bottom)
				(hide yes)
			)
		)
		(pin "1"
		)
		(instances
			(project "jetson-agx-thor-baseboard"
				(path ""
					(reference "#PWR08")
					(unit 1)
				)
			)
		)
	)
	(symbol
		(lib_id "antmicroTestPoints:TP_0.75mm_SMD")
		(at 118.11 153.67 0)
		(mirror y)
		(unit 1)
		(exclude_from_sim no)
		(in_bom no)
		(on_board yes)
		(dnp no)
		(property "Reference" "TP110"
			(at 113.792 153.67 0)
			(effects
				(font
					(size 1.27 1.27)
					(thickness 0.15)
				)
				(justify left)
			)
		)
		(property "Value" "TP_0.75mm_SMD"
			(at 107.95 157.48 0)
			(effects
				(font
					(size 1.27 1.27)
					(thickness 0.15)
				)
				(justify left bottom)
				(hide yes)
			)
		)
		(property "Footprint" "antmicro-footprints:TP_SMD_0.75mm"
			(at 107.95 160.02 0)
			(effects
				(font
					(size 1.27 1.27)
					(thickness 0.15)
				)
				(justify left bottom)
				(hide yes)
			)
		)
		(property "Datasheet" ""
			(at 100.33 166.37 0)
			(effects
				(font
					(size 1.27 1.27)
					(thickness 0.15)
				)
				(justify left bottom)
				(hide yes)
			)
		)
		(property "Description" "SMT test point"
			(at 107.315 167.64 0)
			(effects
				(font
					(size 1.27 1.27)
				)
				(justify left bottom)
				(hide yes)
			)
		)
		(property "MPN" ""
			(at 107.315 165.1 0)
			(effects
				(font
					(size 1.27 1.27)
					(thickness 0.15)
				)
				(justify left bottom)
				(hide yes)
			)
		)
		(property "Manufacturer" ""
			(at 107.315 160.02 0)
			(effects
				(font
					(size 1.27 1.27)
					(thickness 0.15)
				)
				(justify left bottom)
				(hide yes)
			)
		)
		(property "Author" "Antmicro"
			(at 107.95 162.56 0)
			(effects
				(font
					(size 1.27 1.27)
					(thickness 0.15)
				)
				(justify left bottom)
				(hide yes)
			)
		)
		(property "License" "Apache-2.0"
			(at 107.95 165.1 0)
			(effects
				(font
					(size 1.27 1.27)
					(thickness 0.15)
				)
				(justify left bottom)
				(hide yes)
			)
		)
		(pin "1"
		)
		(instances
			(project "jetson-agx-thor-baseboard"
				(path ""
					(reference "TP110")
					(unit 1)
				)
			)
		)
	)
	(symbol
		(lib_id "antmicroResistors0603:R_0R_22.4A_0603")
		(at 382.27 226.06 0)
		(unit 1)
		(exclude_from_sim no)
		(in_bom no)
		(on_board yes)
		(dnp yes)
		(property "Reference" "R250"
			(at 384.81 224.155 0)
			(effects
				(font
					(size 1.27 1.27)
					(thickness 0.15)
				)
			)
		)
		(property "Value" "R_0R_22.4A_0603"
			(at 384.81 217.17 0)
			(effects
				(font
					(size 1.27 1.27)
					(thickness 0.15)
				)
				(hide yes)
			)
		)
		(property "Footprint" "antmicro-footprints:R_0603_1608Metric"
			(at 397.51 236.22 0)
			(effects
				(font
					(size 1.27 1.27)
					(thickness 0.15)
				)
				(justify left bottom)
				(hide yes)
			)
		)
		(property "Datasheet" "https://fscdn.rohm.com/en/products/databook/datasheet/passive/resistor/chip_resistor/pmr-jpw-e.pdf"
			(at 397.51 238.76 0)
			(effects
				(font
					(size 1.27 1.27)
					(thickness 0.15)
				)
				(justify left bottom)
				(hide yes)
			)
		)
		(property "Description" "SMD Chip Resistor"
			(at 382.27 226.06 0)
			(effects
				(font
					(size 1.27 1.27)
				)
				(hide yes)
			)
		)
		(property "MPN" "PMR03EZPJ000"
			(at 397.51 241.3 0)
			(effects
				(font
					(size 1.27 1.27)
					(thickness 0.15)
				)
				(justify left bottom)
				(hide yes)
			)
		)
		(property "Manufacturer" "ROHM Semiconductor"
			(at 397.51 243.84 0)
			(effects
				(font
					(size 1.27 1.27)
					(thickness 0.15)
				)
				(justify left bottom)
				(hide yes)
			)
		)
		(property "Val" "0R"
			(at 387.35 228.6 0)
			(effects
				(font
					(size 1.27 1.27)
					(thickness 0.15)
				)
			)
		)
		(property "Max. Curr." "22.4A"
			(at 382.27 228.6 0)
			(effects
				(font
					(size 1.27 1.27)
					(thickness 0.15)
				)
			)
		)
		(property "Author" "Antmicro"
			(at 397.51 248.92 0)
			(effects
				(font
					(size 1.27 1.27)
					(thickness 0.15)
				)
				(justify left bottom)
				(hide yes)
			)
		)
		(property "License" "Apache-2.0"
			(at 397.51 251.46 0)
			(effects
				(font
					(size 1.27 1.27)
					(thickness 0.15)
				)
				(justify left bottom)
				(hide yes)
			)
		)
		(property "Tolerance" "template_tolerance"
			(at 402.59 236.22 0)
			(effects
				(font
					(size 1.27 1.27)
				)
				(justify left bottom)
				(hide yes)
			)
		)
		(pin "1"
		)
		(pin "2"
		)
		(instances
			(project "jetson-agx-thor-baseboard"
				(path ""
					(reference "R250")
					(unit 1)
				)
			)
		)
	)
	(symbol
		(lib_id "antmicropower:GND")
		(at 82.55 254 0)
		(unit 1)
		(exclude_from_sim no)
		(in_bom yes)
		(on_board yes)
		(dnp no)
		(fields_autoplaced yes)
		(property "Reference" "#PWR0447"
			(at 91.44 256.54 0)
			(effects
				(font
					(size 1.27 1.27)
					(thickness 0.15)
				)
				(justify left bottom)
				(hide yes)
			)
		)
		(property "Value" "GND"
			(at 82.55 259.08 0)
			(effects
				(font
					(size 1.27 1.27)
					(thickness 0.15)
				)
			)
		)
		(property "Footprint" ""
			(at 91.44 261.62 0)
			(effects
				(font
					(size 1.27 1.27)
					(thickness 0.15)
				)
				(justify left bottom)
				(hide yes)
			)
		)
		(property "Datasheet" ""
			(at 91.44 266.7 0)
			(effects
				(font
					(size 1.27 1.27)
					(thickness 0.15)
				)
				(justify left bottom)
				(hide yes)
			)
		)
		(property "Description" ""
			(at 82.55 254 0)
			(effects
				(font
					(size 1.27 1.27)
				)
				(hide yes)
			)
		)
		(property "Author" "Antmicro"
			(at 91.44 261.62 0)
			(effects
				(font
					(size 1.27 1.27)
					(thickness 0.15)
				)
				(justify left bottom)
				(hide yes)
			)
		)
		(property "License" "Apache-2.0"
			(at 91.44 264.16 0)
			(effects
				(font
					(size 1.27 1.27)
					(thickness 0.15)
				)
				(justify left bottom)
				(hide yes)
			)
		)
		(pin "1"
		)
		(instances
			(project "jetson-agx-thor-baseboard"
				(path ""
					(reference "#PWR0447")
					(unit 1)
				)
			)
		)
	)
	(symbol
		(lib_id "antmicroTestPoints:TP_0.75mm_SMD")
		(at 146.05 250.19 0)
		(unit 1)
		(exclude_from_sim no)
		(in_bom no)
		(on_board yes)
		(dnp no)
		(property "Reference" "TP112"
			(at 150.876 250.19 0)
			(effects
				(font
					(size 1.27 1.27)
					(thickness 0.15)
				)
				(justify left)
			)
		)
		(property "Value" "TP_0.75mm_SMD"
			(at 156.21 254 0)
			(effects
				(font
					(size 1.27 1.27)
					(thickness 0.15)
				)
				(justify left bottom)
				(hide yes)
			)
		)
		(property "Footprint" "antmicro-footprints:TP_SMD_0.75mm"
			(at 156.21 256.54 0)
			(effects
				(font
					(size 1.27 1.27)
					(thickness 0.15)
				)
				(justify left bottom)
				(hide yes)
			)
		)
		(property "Datasheet" ""
			(at 163.83 262.89 0)
			(effects
				(font
					(size 1.27 1.27)
					(thickness 0.15)
				)
				(justify left bottom)
				(hide yes)
			)
		)
		(property "Description" "SMT test point"
			(at 156.845 264.16 0)
			(effects
				(font
					(size 1.27 1.27)
				)
				(justify left bottom)
				(hide yes)
			)
		)
		(property "MPN" ""
			(at 156.845 261.62 0)
			(effects
				(font
					(size 1.27 1.27)
					(thickness 0.15)
				)
				(justify left bottom)
				(hide yes)
			)
		)
		(property "Manufacturer" ""
			(at 156.845 256.54 0)
			(effects
				(font
					(size 1.27 1.27)
					(thickness 0.15)
				)
				(justify left bottom)
				(hide yes)
			)
		)
		(property "Author" "Antmicro"
			(at 156.21 259.08 0)
			(effects
				(font
					(size 1.27 1.27)
					(thickness 0.15)
				)
				(justify left bottom)
				(hide yes)
			)
		)
		(property "License" "Apache-2.0"
			(at 156.21 261.62 0)
			(effects
				(font
					(size 1.27 1.27)
					(thickness 0.15)
				)
				(justify left bottom)
				(hide yes)
			)
		)
		(pin "1"
		)
		(instances
			(project "jetson-agx-thor-baseboard"
				(path ""
					(reference "TP112")
					(unit 1)
				)
			)
		)
	)
)
